FILE_TYPE = MACRO_DRAWING;
SET COLOR_WIRE YELLOW;
SET COLOR_PROP ORANGE;
SET COLOR_DOT WHITE;
SET COLOR_ARC YELLOW;
SET COLOR_BODY GREEN;
SET COLOR_NOTE PURPLE;
SET PROP_DISPLAY VALUE;
SET PAGE_NUMBER P52;
SET PATH_NUMBER P147;
FORCEADD OFFPAGE..4
R 2
(-2725 1325);
FORCEPROP 2 LAST $XR0 52 
J 0
(-2946 1325);
DISPLAY 0.638298 (-2946 1325);
PAINT MONO (-2946 1325);
FORCEPROP 2 LAST PATH I1
J 0
(-2925 1375);
DISPLAY 1.021277 (-2925 1375);
DISPLAY INVISIBLE (-2925 1375);
FORCEPROP 2 LAST CDS_LIB standard
J 0
(-2725 1325);
DISPLAY INVISIBLE (-2725 1325);
FORCEPROP 1 LAST OFFPAGE TRUE
J 2
(-3050 1200);
DISPLAY 0.872340 (-3050 1200);
PAINT GREEN (-3050 1200);
DISPLAY INVISIBLE (-3050 1200);
FORCEPROP 1 LAST COMMENT_BODY TRUE
J 2
(-2700 1225);
DISPLAY 0.872340 (-2700 1225);
PAINT PEACH (-2700 1225);
DISPLAY INVISIBLE (-2700 1225);
FORCEADD UNIVERSAL_GND..1
(-3375 1925);
FORCEPROP 3 LASTPIN (-3375 1975) SIG_NAME GND\g
J 0
(-3365 1985);
DISPLAY 0.659574 (-3365 1985);
PAINT MONO (-3365 1985);
DISPLAY INVISIBLE (-3365 1985);
FORCEPROP 1 LAST HDL_POWER GND
J 1
(-3350 1850);
DISPLAY 0.702128 (-3350 1850);
PAINT GREEN (-3350 1850);
DISPLAY INVISIBLE (-3350 1850);
FORCEPROP 1 LAST PATH I100
J 0
(-3300 1925);
DISPLAY 0.872340 (-3300 1925);
PAINT AQUA (-3300 1925);
DISPLAY INVISIBLE (-3300 1925);
FORCEPROP 2 LAST CDS_LIB logical_power
J 0
(-3375 1925);
DISPLAY INVISIBLE (-3375 1925);
FORCEADD Q_CAP..1
(-3375 2125);
FORCEPROP 1 LAST VALUE 0.1UF
J 0
(-3325 2175);
DISPLAY 0.510638 (-3325 2175);
PAINT SKYBLUE (-3325 2175);
FORCEPROP 1 LAST MATERIAL X7R
J 0
(-3325 2025);
DISPLAY 0.510638 (-3325 2025);
PAINT SKYBLUE (-3325 2025);
FORCEPROP 1 LAST PACK_TYPE 0402
J 0
(-3325 1925);
DISPLAY 0.510638 (-3325 1925);
PAINT SKYBLUE (-3325 1925);
FORCEPROP 1 LAST VOLTAGE 25V
J 0
(-3325 2125);
DISPLAY 0.510638 (-3325 2125);
PAINT SKYBLUE (-3325 2125);
FORCEPROP 1 LAST PART_NUMBER CH4104K1B00
J 0
(-3325 1975);
DISPLAY 0.510638 (-3325 1975);
PAINT WHITE (-3325 1975);
FORCEPROP 1 LAST TOLERANCE 10%
J 0
(-3325 2075);
DISPLAY 0.510638 (-3325 2075);
PAINT SKYBLUE (-3325 2075);
FORCEPROP 1 LAST PATH I101
J 0
(-3325 2275);
DISPLAY 0.978723 (-3325 2275);
PAINT WHITE (-3325 2275);
DISPLAY INVISIBLE (-3325 2275);
FORCEPROP 2 LAST CDS_LIB pure_quanta
J 0
(-3375 2125);
DISPLAY INVISIBLE (-3375 2125);
FORCEPROP 1 LAST $LOCATION C262
J 0
(-3325 2225);
DISPLAY 0.978723 (-3325 2225);
FORCEPROP 1 LASTPIN (-3375 2225) $PN 1
J 0
(-3365 2205);
DISPLAY 0.787234 (-3365 2205);
PAINT MONO (-3365 2205);
FORCEPROP 1 LASTPIN (-3375 2025) $PN 2
J 0
(-3365 2005);
DISPLAY 0.787234 (-3365 2005);
PAINT MONO (-3365 2005);
FORCEPROP 0 LAST CDS_LOCATION C262
J 0
(-3325 2275);
DISPLAY 0.680851 (-3325 2275);
DISPLAY INVISIBLE (-3325 2275);
FORCEPROP 0 LAST $SEC 1
J 0
(-3325 2275);
DISPLAY 0.680851 (-3325 2275);
PAINT MONO (-3325 2275);
DISPLAY INVISIBLE (-3325 2275);
FORCEPROP 0 LAST CDS_SEC 1
J 0
(-3325 2275);
DISPLAY 0.680851 (-3325 2275);
DISPLAY INVISIBLE (-3325 2275);
FORCEADD Q_CAP..1
(-2500 2050);
FORCEPROP 1 LAST VALUE 22UF
J 0
(-2450 2100);
DISPLAY 0.510638 (-2450 2100);
PAINT SKYBLUE (-2450 2100);
FORCEPROP 1 LAST PACK_TYPE C0805
J 0
(-2450 1850);
DISPLAY 0.510638 (-2450 1850);
PAINT SKYBLUE (-2450 1850);
FORCEPROP 1 LAST VOLTAGE 16V
J 0
(-2450 2050);
DISPLAY 0.510638 (-2450 2050);
PAINT SKYBLUE (-2450 2050);
FORCEPROP 1 LAST PART_NUMBER CH6223MEA01
J 0
(-2450 1900);
DISPLAY 0.510638 (-2450 1900);
PAINT WHITE (-2450 1900);
FORCEPROP 1 LAST TOLERANCE 20%
J 0
(-2450 2000);
DISPLAY 0.510638 (-2450 2000);
PAINT SKYBLUE (-2450 2000);
FORCEPROP 1 LAST MATERIAL X6S
J 0
(-2450 1950);
DISPLAY 0.510638 (-2450 1950);
PAINT SKYBLUE (-2450 1950);
FORCEPROP 1 LAST PATH I102
J 0
(-2450 2200);
DISPLAY 0.978723 (-2450 2200);
PAINT WHITE (-2450 2200);
DISPLAY INVISIBLE (-2450 2200);
FORCEPROP 2 LAST CDS_LIB pure_quanta
J 0
(-2500 2050);
DISPLAY INVISIBLE (-2500 2050);
FORCEPROP 1 LAST $LOCATION C265
J 0
(-2450 2150);
DISPLAY 0.702128 (-2450 2150);
PAINT AQUA (-2450 2150);
FORCEPROP 1 LASTPIN (-2500 2150) $PN 1
J 0
(-2490 2130);
DISPLAY 0.787234 (-2490 2130);
PAINT MONO (-2490 2130);
FORCEPROP 1 LASTPIN (-2500 1950) $PN 2
J 0
(-2490 1930);
DISPLAY 0.787234 (-2490 1930);
PAINT MONO (-2490 1930);
FORCEPROP 0 LAST CDS_LOCATION C265
J 0
(-2450 2200);
DISPLAY 0.680851 (-2450 2200);
DISPLAY INVISIBLE (-2450 2200);
FORCEPROP 0 LAST $SEC 1
J 0
(-2450 2200);
DISPLAY 0.680851 (-2450 2200);
PAINT MONO (-2450 2200);
DISPLAY INVISIBLE (-2450 2200);
FORCEPROP 0 LAST CDS_SEC 1
J 0
(-2450 2200);
DISPLAY 0.680851 (-2450 2200);
DISPLAY INVISIBLE (-2450 2200);
FORCEADD MC74VHC1G32DTT1G..1
(1725 2600);
FORCEPROP 2 LAST VALUE MC74VHC1G32DTT1G
J 0
(1325 3125);
DISPLAY 0.680851 (1325 3125);
FORCEPROP 1 LAST PART_NUMBER AL001G32031
J 0
(1330 3009);
DISPLAY 0.723404 (1330 3009);
PAINT GREEN (1330 3009);
FORCEPROP 2 LAST PART_TYPE SMLF
J 0
(1325 3175);
DISPLAY 0.680851 (1325 3175);
FORCEPROP 1 LAST MATERIAL IC
J 0
(1330 2882);
DISPLAY 0.723404 (1330 2882);
PAINT GREEN (1330 2882);
FORCEPROP 1 LAST NEEDS_NO_SIZE TRUE
J 0
(1725 2600);
DISPLAY 0.723404 (1725 2600);
PAINT GREEN (1725 2600);
DISPLAY INVISIBLE (1725 2600);
FORCEPROP 1 LAST CDS_LMAN_SYM_OUTLINE -400,275,400,-275
J 0
(1725 2600);
DISPLAY 0.468085 (1725 2600);
PAINT GREEN (1725 2600);
DISPLAY INVISIBLE (1725 2600);
FORCEPROP 1 LAST PATH I104
J 0
(1725 2600);
DISPLAY 0.723404 (1725 2600);
PAINT GREEN (1725 2600);
DISPLAY INVISIBLE (1725 2600);
FORCEPROP 2 LAST CDS_LIB pure_quanta
J 0
(1725 2600);
DISPLAY INVISIBLE (1725 2600);
FORCEPROP 1 LAST $LOCATION U42
J 0
(1325 2950);
DISPLAY 0.723404 (1325 2950);
PAINT GREEN (1325 2950);
FORCEPROP 0 LASTPIN (1175 2425) $PN 3
J 2
(1165 2435);
DISPLAY 0.680851 (1165 2435);
PAINT MONO (1165 2435);
FORCEPROP 0 LASTPIN (1175 2575) $PN 2
J 2
(1165 2585);
DISPLAY 0.680851 (1165 2585);
PAINT MONO (1165 2585);
FORCEPROP 0 LASTPIN (1175 2775) $PN 1
J 2
(1165 2785);
DISPLAY 0.680851 (1165 2785);
PAINT MONO (1165 2785);
FORCEPROP 0 LASTPIN (2275 2425) $PN 4
J 0
(2285 2435);
DISPLAY 0.680851 (2285 2435);
PAINT MONO (2285 2435);
FORCEPROP 0 LASTPIN (2275 2775) $PN 5
J 0
(2285 2785);
DISPLAY 0.680851 (2285 2785);
PAINT MONO (2285 2785);
FORCEPROP 0 LAST CDS_LOCATION U42
J 0
(1325 3225);
DISPLAY 0.680851 (1325 3225);
DISPLAY INVISIBLE (1325 3225);
FORCEPROP 0 LAST $SEC 1
J 0
(1325 3225);
DISPLAY 0.680851 (1325 3225);
PAINT MONO (1325 3225);
DISPLAY INVISIBLE (1325 3225);
FORCEPROP 0 LAST CDS_SEC 1
J 0
(1325 3225);
DISPLAY 0.680851 (1325 3225);
DISPLAY INVISIBLE (1325 3225);
FORCEADD OFFPAGE..4
R 2
(500 2775);
FORCEPROP 2 LAST $XR5 56 
J 0
(-201 2775);
DISPLAY 0.638298 (-201 2775);
PAINT MONO (-201 2775);
FORCEPROP 2 LAST $XR4 55 
J 0
(-111 2775);
DISPLAY 0.638298 (-111 2775);
PAINT MONO (-111 2775);
FORCEPROP 2 LAST $XR3 54 
J 0
(-21 2775);
DISPLAY 0.638298 (-21 2775);
PAINT MONO (-21 2775);
FORCEPROP 2 LAST $XR2 52 
J 0
(69 2775);
DISPLAY 0.638298 (69 2775);
PAINT MONO (69 2775);
FORCEPROP 2 LAST $XR1 35 
J 0
(159 2775);
DISPLAY 0.638298 (159 2775);
PAINT MONO (159 2775);
FORCEPROP 2 LAST $XR0 51 
J 0
(249 2775);
DISPLAY 0.638298 (249 2775);
PAINT MONO (249 2775);
FORCEPROP 2 LAST PATH I105
J 0
(250 2825);
DISPLAY 0.680851 (250 2825);
DISPLAY INVISIBLE (250 2825);
FORCEPROP 1 LAST COMMENT_BODY TRUE
J 2
(525 2675);
DISPLAY 0.872340 (525 2675);
PAINT PEACH (525 2675);
DISPLAY INVISIBLE (525 2675);
FORCEPROP 1 LAST OFFPAGE TRUE
J 2
(175 2650);
DISPLAY 0.872340 (175 2650);
PAINT GREEN (175 2650);
DISPLAY INVISIBLE (175 2650);
FORCEPROP 2 LAST CDS_LIB standard
J 0
(500 2775);
DISPLAY INVISIBLE (500 2775);
FORCEADD Q_CAP..1
R 2
(2250 3100);
FORCEPROP 1 LAST TOLERANCE 10%
J 2
(2200 3025);
DISPLAY 0.510638 (2200 3025);
PAINT SKYBLUE (2200 3025);
FORCEPROP 1 LAST VALUE 0.1UF
J 2
(2200 3125);
DISPLAY 0.510638 (2200 3125);
PAINT SKYBLUE (2200 3125);
FORCEPROP 1 LAST VOLTAGE 25V
J 2
(2200 3075);
DISPLAY 0.510638 (2200 3075);
PAINT SKYBLUE (2200 3075);
FORCEPROP 1 LAST MATERIAL X7R
J 2
(2200 2975);
DISPLAY 0.510638 (2200 2975);
PAINT SKYBLUE (2200 2975);
FORCEPROP 1 LAST PACK_TYPE 0402
J 2
(2200 2925);
DISPLAY 0.510638 (2200 2925);
PAINT SKYBLUE (2200 2925);
FORCEPROP 1 LAST PART_NUMBER CH4104K1B00
J 2
(2200 2875);
DISPLAY 0.510638 (2200 2875);
PAINT WHITE (2200 2875);
FORCEPROP 1 LAST PATH I107
J 2
(2200 3250);
DISPLAY 0.978723 (2200 3250);
PAINT WHITE (2200 3250);
DISPLAY INVISIBLE (2200 3250);
FORCEPROP 2 LAST CDS_LIB pure_quanta
J 0
(2250 3100);
DISPLAY INVISIBLE (2250 3100);
FORCEPROP 1 LAST $LOCATION C297
J 2
(2200 3200);
DISPLAY 0.978723 (2200 3200);
FORCEPROP 1 LASTPIN (2250 3200) $PN 1
J 2
(2240 3180);
DISPLAY 0.787234 (2240 3180);
PAINT MONO (2240 3180);
FORCEPROP 1 LASTPIN (2250 3000) $PN 2
J 2
(2240 2980);
DISPLAY 0.787234 (2240 2980);
PAINT MONO (2240 2980);
FORCEPROP 0 LAST CDS_LOCATION C297
J 0
(2200 3250);
DISPLAY 0.680851 (2200 3250);
DISPLAY INVISIBLE (2200 3250);
FORCEPROP 0 LAST $SEC 1
J 0
(2200 3250);
DISPLAY 0.680851 (2200 3250);
PAINT MONO (2200 3250);
DISPLAY INVISIBLE (2200 3250);
FORCEPROP 0 LAST CDS_SEC 1
J 0
(2200 3250);
DISPLAY 0.680851 (2200 3250);
DISPLAY INVISIBLE (2200 3250);
FORCEADD UNIVERSAL_GND..1
(2250 2900);
FORCEPROP 3 LASTPIN (2250 2950) SIG_NAME GND\g
J 0
(2260 2960);
DISPLAY 0.659574 (2260 2960);
PAINT MONO (2260 2960);
DISPLAY INVISIBLE (2260 2960);
FORCEPROP 1 LAST HDL_POWER GND
J 1
(2275 2825);
DISPLAY 0.702128 (2275 2825);
PAINT GREEN (2275 2825);
DISPLAY INVISIBLE (2275 2825);
FORCEPROP 1 LAST PATH I109
J 0
(2325 2900);
DISPLAY 0.872340 (2325 2900);
PAINT AQUA (2325 2900);
DISPLAY INVISIBLE (2325 2900);
FORCEPROP 2 LAST CDS_LIB logical_power
J 0
(2250 2900);
DISPLAY INVISIBLE (2250 2900);
FORCEADD Q_CAP..1
(-1175 2050);
FORCEPROP 1 LAST VALUE 0.1UF
J 0
(-1125 2100);
DISPLAY 0.510638 (-1125 2100);
PAINT SKYBLUE (-1125 2100);
FORCEPROP 1 LAST VOLTAGE 25V
J 0
(-1125 2050);
DISPLAY 0.510638 (-1125 2050);
PAINT SKYBLUE (-1125 2050);
FORCEPROP 1 LAST PACK_TYPE 0402
J 0
(-1125 1850);
DISPLAY 0.510638 (-1125 1850);
PAINT SKYBLUE (-1125 1850);
FORCEPROP 1 LAST MATERIAL X7R
J 0
(-1125 1950);
DISPLAY 0.510638 (-1125 1950);
PAINT SKYBLUE (-1125 1950);
FORCEPROP 1 LAST TOLERANCE 10%
J 0
(-1125 2000);
DISPLAY 0.510638 (-1125 2000);
PAINT SKYBLUE (-1125 2000);
FORCEPROP 1 LAST PART_NUMBER CH4104K1B00
J 0
(-1125 1900);
DISPLAY 0.510638 (-1125 1900);
PAINT WHITE (-1125 1900);
FORCEPROP 2 LAST SEC_TYPE 0402
J 0
(-1125 2250);
DISPLAY 1.021277 (-1125 2250);
DISPLAY INVISIBLE (-1125 2250);
FORCEPROP 2 LAST CDS_LIB pure_quanta
J 0
(-1175 2050);
DISPLAY INVISIBLE (-1175 2050);
FORCEPROP 1 LAST PATH I11
J 0
(-1125 2200);
DISPLAY 0.978723 (-1125 2200);
PAINT WHITE (-1125 2200);
DISPLAY INVISIBLE (-1125 2200);
FORCEPROP 1 LAST LOCATION PC223
J 0
(-1125 2150);
DISPLAY 0.702128 (-1125 2150);
PAINT AQUA (-1125 2150);
FORCEPROP 1 LASTPIN (-1175 2150) $PN 1
J 0
(-1165 2130);
DISPLAY 0.808511 (-1165 2130);
PAINT WHITE (-1165 2130);
FORCEPROP 1 LASTPIN (-1175 1950) $PN 2
J 0
(-1165 1930);
DISPLAY 0.808511 (-1165 1930);
PAINT WHITE (-1165 1930);
FORCEPROP 2 LAST SEC 1
J 0
(-1125 2250);
DISPLAY 0.680851 (-1125 2250);
PAINT MONO (-1125 2250);
DISPLAY INVISIBLE (-1125 2250);
FORCEADD UNIVERSAL_GND..1
(1075 2300);
FORCEPROP 3 LASTPIN (1075 2350) SIG_NAME GND\g
J 0
(1085 2360);
DISPLAY 0.659574 (1085 2360);
PAINT MONO (1085 2360);
DISPLAY INVISIBLE (1085 2360);
FORCEPROP 2 LAST CDS_LIB logical_power
J 0
(1075 2300);
DISPLAY INVISIBLE (1075 2300);
FORCEPROP 1 LAST PATH I112
J 0
(1150 2300);
DISPLAY 0.872340 (1150 2300);
PAINT AQUA (1150 2300);
DISPLAY INVISIBLE (1150 2300);
FORCEPROP 1 LAST HDL_POWER GND
J 1
(1100 2225);
DISPLAY 0.702128 (1100 2225);
PAINT GREEN (1100 2225);
DISPLAY INVISIBLE (1100 2225);
FORCEADD OFFPAGE..4
R 2
(500 2575);
FORCEPROP 2 LAST $XR3 55 
J 0
(-21 2575);
DISPLAY 0.638298 (-21 2575);
PAINT MONO (-21 2575);
FORCEPROP 2 LAST $XR2 52 
J 0
(69 2575);
DISPLAY 0.638298 (69 2575);
PAINT MONO (69 2575);
FORCEPROP 2 LAST $XR1 36 
J 0
(159 2575);
DISPLAY 0.638298 (159 2575);
PAINT MONO (159 2575);
FORCEPROP 2 LAST $XR0 54 
J 0
(249 2575);
DISPLAY 0.638298 (249 2575);
PAINT MONO (249 2575);
FORCEPROP 1 LAST COMMENT_BODY TRUE
J 2
(525 2475);
DISPLAY 0.872340 (525 2475);
PAINT PEACH (525 2475);
DISPLAY INVISIBLE (525 2475);
FORCEPROP 1 LAST OFFPAGE TRUE
J 2
(175 2450);
DISPLAY 0.872340 (175 2450);
PAINT GREEN (175 2450);
DISPLAY INVISIBLE (175 2450);
FORCEPROP 2 LAST CDS_LIB standard
J 0
(500 2575);
DISPLAY INVISIBLE (500 2575);
FORCEPROP 2 LAST PATH I113
J 0
(250 2625);
DISPLAY 0.680851 (250 2625);
DISPLAY INVISIBLE (250 2625);
FORCEADD 74LVC1G08GW..1
(3600 -1400);
FORCEPROP 2 LAST PACK_TYPE SM
J 0
(3750 -1450);
DISPLAY 0.680851 (3750 -1450);
FORCEPROP 1 LAST MATERIAL IC
J 0
(3750 -1590);
DISPLAY 0.723404 (3750 -1590);
PAINT GREEN (3750 -1590);
FORCEPROP 2 LAST VALUE 74LVC1G08GW
J 0
(3650 -1275);
DISPLAY 0.680851 (3650 -1275);
FORCEPROP 1 LAST PART_NUMBER ALVC1G08009
J 0
(3750 -1540);
DISPLAY 0.723404 (3750 -1540);
PAINT GREEN (3750 -1540);
FORCEPROP 1 LAST PATH I114
J 0
(3875 -1595);
DISPLAY 0.723404 (3875 -1595);
PAINT GREEN (3875 -1595);
DISPLAY INVISIBLE (3875 -1595);
FORCEPROP 1 LAST NEEDS_NO_SIZE TRUE
J 0
(3600 -1400);
DISPLAY 0.468085 (3600 -1400);
PAINT GREEN (3600 -1400);
DISPLAY INVISIBLE (3600 -1400);
FORCEPROP 2 LAST CDS_LIB pure_quanta
J 0
(3600 -1400);
DISPLAY INVISIBLE (3600 -1400);
FORCEPROP 1 LAST $LOCATION U18
J 0
(3750 -1495);
DISPLAY 0.723404 (3750 -1495);
PAINT GREEN (3750 -1495);
FORCEPROP 0 LASTPIN (3300 -1450) $PN 2
J 2
(3290 -1440);
DISPLAY 0.680851 (3290 -1440);
PAINT MONO (3290 -1440);
FORCEPROP 0 LASTPIN (3300 -1350) $PN 1
J 2
(3290 -1340);
DISPLAY 0.680851 (3290 -1340);
PAINT MONO (3290 -1340);
FORCEPROP 0 LASTPIN (3550 -1650) $PN 3
R 1
J 2
(3540 -1660);
DISPLAY 0.680851 (3540 -1660);
PAINT MONO (3540 -1660);
FORCEPROP 0 LASTPIN (3550 -1150) $PN 5
R 1
J 0
(3540 -1140);
DISPLAY 0.680851 (3540 -1140);
PAINT MONO (3540 -1140);
FORCEPROP 0 LASTPIN (3900 -1400) $PN 4
J 0
(3910 -1390);
DISPLAY 0.680851 (3910 -1390);
PAINT MONO (3910 -1390);
FORCEPROP 0 LAST CDS_LOCATION U18
J 0
(3650 -1225);
DISPLAY 0.680851 (3650 -1225);
DISPLAY INVISIBLE (3650 -1225);
FORCEPROP 0 LAST $SEC 1
J 0
(3650 -1225);
DISPLAY 0.680851 (3650 -1225);
PAINT MONO (3650 -1225);
DISPLAY INVISIBLE (3650 -1225);
FORCEPROP 0 LAST CDS_SEC 1
J 0
(3650 -1225);
DISPLAY 0.680851 (3650 -1225);
DISPLAY INVISIBLE (3650 -1225);
FORCEADD OFFPAGE..4
R 2
(2775 -1100);
FORCEPROP 2 LAST $XR5 56 
J 0
(2074 -1100);
DISPLAY 0.638298 (2074 -1100);
PAINT MONO (2074 -1100);
FORCEPROP 2 LAST $XR4 55 
J 0
(2164 -1100);
DISPLAY 0.638298 (2164 -1100);
PAINT MONO (2164 -1100);
FORCEPROP 2 LAST $XR3 54 
J 0
(2254 -1100);
DISPLAY 0.638298 (2254 -1100);
PAINT MONO (2254 -1100);
FORCEPROP 2 LAST $XR2 52 
J 0
(2344 -1100);
DISPLAY 0.638298 (2344 -1100);
PAINT MONO (2344 -1100);
FORCEPROP 2 LAST $XR1 35 
J 0
(2434 -1100);
DISPLAY 0.638298 (2434 -1100);
PAINT MONO (2434 -1100);
FORCEPROP 2 LAST $XR0 51 
J 0
(2524 -1100);
DISPLAY 0.638298 (2524 -1100);
PAINT MONO (2524 -1100);
FORCEPROP 1 LAST COMMENT_BODY TRUE
J 2
(2800 -1200);
DISPLAY 0.872340 (2800 -1200);
PAINT PEACH (2800 -1200);
DISPLAY INVISIBLE (2800 -1200);
FORCEPROP 1 LAST OFFPAGE TRUE
J 2
(2450 -1225);
DISPLAY 0.872340 (2450 -1225);
PAINT GREEN (2450 -1225);
DISPLAY INVISIBLE (2450 -1225);
FORCEPROP 2 LAST CDS_LIB standard
J 0
(2775 -1100);
DISPLAY INVISIBLE (2775 -1100);
FORCEPROP 2 LAST PATH I115
J 0
(2525 -1050);
DISPLAY 0.680851 (2525 -1050);
DISPLAY INVISIBLE (2525 -1050);
FORCEADD UNIVERSAL_GND..1
(3900 -1100);
FORCEPROP 3 LASTPIN (3900 -1050) SIG_NAME GND\g
J 0
(3910 -1040);
DISPLAY 0.659574 (3910 -1040);
PAINT MONO (3910 -1040);
DISPLAY INVISIBLE (3910 -1040);
FORCEPROP 2 LAST CDS_LIB logical_power
J 0
(3900 -1100);
DISPLAY INVISIBLE (3900 -1100);
FORCEPROP 1 LAST PATH I118
J 0
(3975 -1100);
DISPLAY 0.872340 (3975 -1100);
PAINT AQUA (3975 -1100);
DISPLAY INVISIBLE (3975 -1100);
FORCEPROP 1 LAST HDL_POWER GND
J 1
(3925 -1175);
DISPLAY 0.702128 (3925 -1175);
PAINT GREEN (3925 -1175);
DISPLAY INVISIBLE (3925 -1175);
FORCEADD Q_CAP..1
R 2
(3900 -925);
FORCEPROP 1 LAST PART_NUMBER CH4104K1B00
J 2
(3850 -1150);
DISPLAY 0.510638 (3850 -1150);
PAINT WHITE (3850 -1150);
FORCEPROP 1 LAST PACK_TYPE 0402
J 2
(3850 -1100);
DISPLAY 0.510638 (3850 -1100);
PAINT SKYBLUE (3850 -1100);
FORCEPROP 1 LAST MATERIAL X7R
J 2
(3850 -1050);
DISPLAY 0.510638 (3850 -1050);
PAINT SKYBLUE (3850 -1050);
FORCEPROP 1 LAST VALUE 0.1UF
J 2
(3850 -900);
DISPLAY 0.510638 (3850 -900);
PAINT SKYBLUE (3850 -900);
FORCEPROP 1 LAST TOLERANCE 10%
J 2
(3850 -1000);
DISPLAY 0.510638 (3850 -1000);
PAINT SKYBLUE (3850 -1000);
FORCEPROP 1 LAST VOLTAGE 25V
J 2
(3850 -950);
DISPLAY 0.510638 (3850 -950);
PAINT SKYBLUE (3850 -950);
FORCEPROP 1 LAST PATH I119
J 2
(3850 -775);
DISPLAY 0.978723 (3850 -775);
PAINT WHITE (3850 -775);
DISPLAY INVISIBLE (3850 -775);
FORCEPROP 2 LAST CDS_LIB pure_quanta
J 0
(3900 -925);
DISPLAY INVISIBLE (3900 -925);
FORCEPROP 1 LAST $LOCATION C296
J 2
(3850 -825);
DISPLAY 0.787234 (3850 -825);
FORCEPROP 1 LASTPIN (3900 -825) $PN 1
J 2
(3890 -845);
DISPLAY 0.787234 (3890 -845);
PAINT MONO (3890 -845);
FORCEPROP 1 LASTPIN (3900 -1025) $PN 2
J 2
(3890 -1045);
DISPLAY 0.787234 (3890 -1045);
PAINT MONO (3890 -1045);
FORCEPROP 0 LAST CDS_LOCATION C296
J 0
(3850 -775);
DISPLAY 0.680851 (3850 -775);
DISPLAY INVISIBLE (3850 -775);
FORCEPROP 0 LAST $SEC 1
J 0
(3850 -775);
DISPLAY 0.680851 (3850 -775);
PAINT MONO (3850 -775);
DISPLAY INVISIBLE (3850 -775);
FORCEPROP 0 LAST CDS_SEC 1
J 0
(3850 -775);
DISPLAY 0.680851 (3850 -775);
DISPLAY INVISIBLE (3850 -775);
FORCEADD UNIVERSAL_GND..1
(325 225);
FORCEPROP 3 LASTPIN (325 275) SIG_NAME GND\g
J 0
(335 285);
DISPLAY 0.659574 (335 285);
PAINT MONO (335 285);
DISPLAY INVISIBLE (335 285);
FORCEPROP 2 LAST CDS_LIB logical_power
J 0
(325 225);
DISPLAY INVISIBLE (325 225);
FORCEPROP 1 LAST HDL_POWER GND
J 1
(350 150);
DISPLAY 0.702128 (350 150);
PAINT GREEN (350 150);
DISPLAY INVISIBLE (350 150);
FORCEPROP 1 LAST PATH I12
J 0
(400 225);
DISPLAY 0.872340 (400 225);
PAINT AQUA (400 225);
DISPLAY INVISIBLE (400 225);
FORCEADD UNIVERSAL_GND..1
(3550 -1825);
FORCEPROP 3 LASTPIN (3550 -1775) SIG_NAME GND\g
J 0
(3560 -1765);
DISPLAY 0.659574 (3560 -1765);
PAINT MONO (3560 -1765);
DISPLAY INVISIBLE (3560 -1765);
FORCEPROP 1 LAST PATH I120
J 0
(3625 -1825);
DISPLAY 0.872340 (3625 -1825);
PAINT AQUA (3625 -1825);
DISPLAY INVISIBLE (3625 -1825);
FORCEPROP 2 LAST CDS_LIB logical_power
J 0
(3550 -1825);
DISPLAY INVISIBLE (3550 -1825);
FORCEPROP 1 LAST HDL_POWER GND
J 1
(3575 -1900);
DISPLAY 0.702128 (3575 -1900);
PAINT GREEN (3575 -1900);
DISPLAY INVISIBLE (3575 -1900);
FORCEADD OFFPAGE..4
R 2
(1750 -1450);
FORCEPROP 2 LAST $XR3 55 
J 0
(1229 -1450);
DISPLAY 0.638298 (1229 -1450);
PAINT MONO (1229 -1450);
FORCEPROP 2 LAST $XR2 52 
J 0
(1319 -1450);
DISPLAY 0.638298 (1319 -1450);
PAINT MONO (1319 -1450);
FORCEPROP 2 LAST $XR1 36 
J 0
(1409 -1450);
DISPLAY 0.638298 (1409 -1450);
PAINT MONO (1409 -1450);
FORCEPROP 2 LAST $XR0 54 
J 0
(1499 -1450);
DISPLAY 0.638298 (1499 -1450);
PAINT MONO (1499 -1450);
FORCEPROP 2 LAST PATH I122
J 0
(1550 -1400);
DISPLAY 0.680851 (1550 -1400);
DISPLAY INVISIBLE (1550 -1400);
FORCEPROP 2 LAST CDS_LIB standard
J 0
(1750 -1450);
DISPLAY INVISIBLE (1750 -1450);
FORCEPROP 1 LAST OFFPAGE TRUE
J 2
(1425 -1575);
DISPLAY 0.872340 (1425 -1575);
PAINT GREEN (1425 -1575);
DISPLAY INVISIBLE (1425 -1575);
FORCEPROP 1 LAST COMMENT_BODY TRUE
J 2
(1775 -1550);
DISPLAY 0.872340 (1775 -1550);
PAINT PEACH (1775 -1550);
DISPLAY INVISIBLE (1775 -1550);
FORCEADD UNIVERSAL_GND..1
(2925 -1875);
FORCEPROP 3 LASTPIN (2925 -1825) SIG_NAME GND\g
J 0
(2935 -1815);
DISPLAY 0.659574 (2935 -1815);
PAINT MONO (2935 -1815);
DISPLAY INVISIBLE (2935 -1815);
FORCEPROP 1 LAST PATH I124
J 0
(3000 -1875);
DISPLAY 0.872340 (3000 -1875);
PAINT AQUA (3000 -1875);
DISPLAY INVISIBLE (3000 -1875);
FORCEPROP 1 LAST HDL_POWER GND
J 1
(2950 -1950);
DISPLAY 0.702128 (2950 -1950);
PAINT GREEN (2950 -1950);
DISPLAY INVISIBLE (2950 -1950);
FORCEPROP 2 LAST CDS_LIB logical_power
J 0
(2925 -1875);
DISPLAY INVISIBLE (2925 -1875);
FORCEADD Q_CAP..1
(2925 -1650);
FORCEPROP 1 LAST VALUE 1UF
J 0
(2975 -1600);
DISPLAY 0.510638 (2975 -1600);
PAINT SKYBLUE (2975 -1600);
FORCEPROP 1 LAST PACK_TYPE C0402
J 0
(2975 -1850);
DISPLAY 0.510638 (2975 -1850);
PAINT SKYBLUE (2975 -1850);
FORCEPROP 1 LAST MATERIAL X6S
J 0
(2975 -1750);
DISPLAY 0.510638 (2975 -1750);
PAINT SKYBLUE (2975 -1750);
FORCEPROP 1 LAST VOLTAGE 25V
J 0
(2975 -1650);
DISPLAY 0.510638 (2975 -1650);
PAINT SKYBLUE (2975 -1650);
FORCEPROP 1 LAST TOLERANCE 10%
J 0
(2975 -1700);
DISPLAY 0.510638 (2975 -1700);
PAINT SKYBLUE (2975 -1700);
FORCEPROP 1 LAST PART_NUMBER CH5104KEB02
J 0
(2975 -1800);
DISPLAY 0.510638 (2975 -1800);
PAINT WHITE (2975 -1800);
FORCEPROP 1 LAST PATH I125
J 0
(2975 -1500);
DISPLAY 0.978723 (2975 -1500);
PAINT WHITE (2975 -1500);
DISPLAY INVISIBLE (2975 -1500);
FORCEPROP 2 LAST CDS_LIB pure_quanta
J 0
(2925 -1650);
DISPLAY INVISIBLE (2925 -1650);
FORCEPROP 1 LAST $LOCATION C305
J 0
(2975 -1550);
DISPLAY 0.702128 (2975 -1550);
PAINT YELLOW (2975 -1550);
FORCEPROP 1 LASTPIN (2925 -1550) $PN 1
J 0
(2935 -1570);
DISPLAY 0.787234 (2935 -1570);
PAINT MONO (2935 -1570);
FORCEPROP 1 LASTPIN (2925 -1750) $PN 2
J 0
(2935 -1770);
DISPLAY 0.787234 (2935 -1770);
PAINT MONO (2935 -1770);
FORCEPROP 0 LAST CDS_LOCATION C305
J 0
(2975 -1500);
DISPLAY 0.680851 (2975 -1500);
DISPLAY INVISIBLE (2975 -1500);
FORCEPROP 0 LAST $SEC 1
J 0
(2975 -1500);
DISPLAY 0.680851 (2975 -1500);
PAINT MONO (2975 -1500);
DISPLAY INVISIBLE (2975 -1500);
FORCEPROP 0 LAST CDS_SEC 1
J 0
(2975 -1500);
DISPLAY 0.680851 (2975 -1500);
DISPLAY INVISIBLE (2975 -1500);
FORCEADD Q_RES..1
(2475 -1450);
FORCEPROP 1 LAST VALUE 100
J 2
(2475 -1500);
DISPLAY 0.638298 (2475 -1500);
FORCEPROP 1 LAST TOLERANCE 1%
J 0
(2500 -1500);
DISPLAY 0.638298 (2500 -1500);
FORCEPROP 1 LAST MATERIAL CHIP
J 0
(2500 -1550);
DISPLAY 0.638298 (2500 -1550);
FORCEPROP 1 LAST WATTAGE 1/16W
J 2
(2475 -1550);
DISPLAY 0.638298 (2475 -1550);
FORCEPROP 1 LAST PART_NUMBER CS11002FB07
J 0
(2425 -1350);
DISPLAY 0.638298 (2425 -1350);
FORCEPROP 1 LAST PACK_TYPE 0402LF
J 0
(2500 -1400);
DISPLAY 0.638298 (2500 -1400);
FORCEPROP 2 LAST CDS_LIB pure_quanta
J 0
(2475 -1450);
DISPLAY INVISIBLE (2475 -1450);
FORCEPROP 1 LAST PATH I127
J 0
(2425 -1300);
DISPLAY 0.978723 (2425 -1300);
PAINT WHITE (2425 -1300);
DISPLAY INVISIBLE (2425 -1300);
FORCEPROP 1 LAST $LOCATION R529
J 0
(2350 -1400);
DISPLAY 0.638298 (2350 -1400);
FORCEPROP 1 LASTPIN (2375 -1450) $PN 1
J 0
(2387 -1438);
DISPLAY 0.787234 (2387 -1438);
PAINT MONO (2387 -1438);
FORCEPROP 1 LASTPIN (2575 -1450) $PN 2
J 0
(2537 -1438);
DISPLAY 0.787234 (2537 -1438);
PAINT MONO (2537 -1438);
FORCEPROP 0 LAST CDS_LOCATION R529
J 0
(2425 -1300);
DISPLAY 0.680851 (2425 -1300);
DISPLAY INVISIBLE (2425 -1300);
FORCEPROP 0 LAST $SEC 1
J 0
(2425 -1300);
DISPLAY 0.680851 (2425 -1300);
PAINT MONO (2425 -1300);
DISPLAY INVISIBLE (2425 -1300);
FORCEPROP 0 LAST CDS_SEC 1
J 0
(2425 -1300);
DISPLAY 0.680851 (2425 -1300);
DISPLAY INVISIBLE (2425 -1300);
FORCEADD Q_RES..2
(325 2075);
FORCEPROP 1 LAST VALUE 10K
J 0
(370 2150);
DISPLAY 0.510638 (370 2150);
PAINT SKYBLUE (370 2150);
FORCEPROP 1 LAST MATERIAL CHIP
J 0
(365 2000);
DISPLAY 0.510638 (365 2000);
PAINT SKYBLUE (365 2000);
FORCEPROP 1 LAST PART_NUMBER CS31002FB08
J 0
(365 1950);
DISPLAY 0.510638 (365 1950);
PAINT WHITE (365 1950);
FORCEPROP 1 LAST PACK_TYPE 0402LF
J 0
(365 1900);
DISPLAY 0.510638 (365 1900);
PAINT SKYBLUE (365 1900);
FORCEPROP 1 LAST WATTAGE 1/16W
J 0
(365 2050);
DISPLAY 0.510638 (365 2050);
PAINT SKYBLUE (365 2050);
FORCEPROP 1 LAST TOLERANCE 1%
J 0
(370 2100);
DISPLAY 0.510638 (370 2100);
PAINT SKYBLUE (370 2100);
FORCEPROP 1 LAST PATH I13
J 0
(375 2250);
DISPLAY 0.978723 (375 2250);
PAINT WHITE (375 2250);
DISPLAY INVISIBLE (375 2250);
FORCEPROP 2 LAST SEC_TYPE 0402LF
J 0
(375 2300);
DISPLAY 1.021277 (375 2300);
DISPLAY INVISIBLE (375 2300);
FORCEPROP 2 LAST CDS_LIB pure_quanta
J 0
(325 2075);
DISPLAY INVISIBLE (325 2075);
FORCEPROP 1 LAST LOCATION PR242
J 0
(370 2200);
DISPLAY 0.702128 (370 2200);
PAINT AQUA (370 2200);
FORCEPROP 1 LASTPIN (325 2175) $PN 1
J 0
(330 2137);
DISPLAY 0.808511 (330 2137);
PAINT WHITE (330 2137);
FORCEPROP 1 LASTPIN (325 1975) $PN 2
J 0
(330 1985);
DISPLAY 0.808511 (330 1985);
PAINT WHITE (330 1985);
FORCEPROP 2 LAST SEC 1
J 0
(375 2300);
DISPLAY 0.680851 (375 2300);
PAINT MONO (375 2300);
DISPLAY INVISIBLE (375 2300);
FORCEADD OFFPAGE..5
R 2
(3100 2425);
FORCEPROP 2 LAST $XR0 52 
J 0
(3289 2425);
DISPLAY 0.638298 (3289 2425);
PAINT MONO (3289 2425);
FORCEPROP 2 LAST PATH I130
J 0
(3300 2475);
DISPLAY 0.680851 (3300 2475);
DISPLAY INVISIBLE (3300 2475);
FORCEPROP 1 LAST COMMENT_BODY TRUE
J 2
(3000 2350);
DISPLAY 0.872340 (3000 2350);
PAINT PEACH (3000 2350);
DISPLAY INVISIBLE (3000 2350);
FORCEPROP 1 LAST OFFPAGE TRUE
J 2
(2775 2300);
DISPLAY 0.872340 (2775 2300);
PAINT GREEN (2775 2300);
DISPLAY INVISIBLE (2775 2300);
FORCEPROP 2 LAST CDS_LIB standard
J 0
(3100 2425);
DISPLAY INVISIBLE (3100 2425);
FORCEADD OFFPAGE..5
R 2
(4550 -1400);
FORCEPROP 2 LAST $XR0 52 
J 0
(4739 -1400);
DISPLAY 0.638298 (4739 -1400);
PAINT MONO (4739 -1400);
FORCEPROP 2 LAST PATH I136
J 0
(4750 -1350);
DISPLAY 0.680851 (4750 -1350);
DISPLAY INVISIBLE (4750 -1350);
FORCEPROP 2 LAST CDS_LIB standard
J 0
(4550 -1400);
DISPLAY INVISIBLE (4550 -1400);
FORCEPROP 1 LAST OFFPAGE TRUE
J 2
(4225 -1525);
DISPLAY 0.872340 (4225 -1525);
PAINT GREEN (4225 -1525);
DISPLAY INVISIBLE (4225 -1525);
FORCEPROP 1 LAST COMMENT_BODY TRUE
J 2
(4450 -1475);
DISPLAY 0.872340 (4450 -1475);
PAINT PEACH (4450 -1475);
DISPLAY INVISIBLE (4450 -1475);
FORCEADD Q_RES..1
(-1625 1550);
FORCEPROP 1 LAST VALUE 0
J 2
(-1775 1550);
DISPLAY 0.978723 (-1775 1550);
FORCEPROP 1 LAST MATERIAL EMPTY
J 0
(-1875 1600);
DISPLAY 0.978723 (-1875 1600);
FORCEPROP 1 LAST PART_NUMBER CS00002JB13
J 0
(-1850 1650);
DISPLAY 0.978723 (-1850 1650);
FORCEPROP 1 LAST PACK_TYPE 0402LF
J 0
(-1675 1475);
DISPLAY 0.978723 (-1675 1475);
FORCEPROP 1 LAST WATTAGE 1/16W
J 2
(-1700 1475);
DISPLAY 0.978723 (-1700 1475);
FORCEPROP 1 LAST TOLERANCE 5%
J 0
(-2025 1475);
DISPLAY 0.978723 (-2025 1475);
FORCEPROP 2 LAST CDS_LIB pure_quanta
J 0
(-1625 1550);
DISPLAY INVISIBLE (-1625 1550);
FORCEPROP 1 LAST PATH I137
J 0
(-1675 1700);
DISPLAY 0.978723 (-1675 1700);
PAINT WHITE (-1675 1700);
DISPLAY INVISIBLE (-1675 1700);
FORCEPROP 1 LAST $LOCATION R871
J 0
(-1650 1600);
DISPLAY 0.978723 (-1650 1600);
FORCEPROP 1 LASTPIN (-1725 1550) $PN 1
J 0
(-1713 1562);
DISPLAY 0.787234 (-1713 1562);
PAINT MONO (-1713 1562);
FORCEPROP 1 LASTPIN (-1525 1550) $PN 2
J 0
(-1563 1562);
DISPLAY 0.787234 (-1563 1562);
PAINT MONO (-1563 1562);
FORCEPROP 0 LAST CDS_LOCATION R871
J 0
(-1850 1700);
DISPLAY 0.680851 (-1850 1700);
DISPLAY INVISIBLE (-1850 1700);
FORCEPROP 0 LAST $SEC 1
J 0
(-1850 1700);
DISPLAY 0.680851 (-1850 1700);
PAINT MONO (-1850 1700);
DISPLAY INVISIBLE (-1850 1700);
FORCEPROP 0 LAST CDS_SEC 1
J 0
(-1850 1700);
DISPLAY 0.680851 (-1850 1700);
DISPLAY INVISIBLE (-1850 1700);
FORCEADD OFFPAGE..4
R 2
(-2725 1550);
FORCEPROP 2 LAST $XR0 51 
J 0
(-2946 1550);
DISPLAY 0.638298 (-2946 1550);
PAINT MONO (-2946 1550);
FORCEPROP 1 LAST COMMENT_BODY TRUE
J 2
(-2700 1450);
DISPLAY 0.872340 (-2700 1450);
PAINT PEACH (-2700 1450);
DISPLAY INVISIBLE (-2700 1450);
FORCEPROP 1 LAST OFFPAGE TRUE
J 2
(-3050 1425);
DISPLAY 0.872340 (-3050 1425);
PAINT GREEN (-3050 1425);
DISPLAY INVISIBLE (-3050 1425);
FORCEPROP 2 LAST CDS_LIB standard
J 0
(-2725 1550);
DISPLAY INVISIBLE (-2725 1550);
FORCEPROP 2 LAST PATH I138
J 0
(-2925 1600);
DISPLAY 0.680851 (-2925 1600);
DISPLAY INVISIBLE (-2925 1600);
FORCEADD Q_RES..1
(-2500 -1550);
FORCEPROP 1 LAST PACK_TYPE 0402LF
J 0
(-2550 -1625);
DISPLAY 0.787234 (-2550 -1625);
FORCEPROP 1 LAST VALUE 0
J 2
(-2650 -1550);
DISPLAY 0.787234 (-2650 -1550);
FORCEPROP 1 LAST TOLERANCE 5%
J 0
(-2650 -1625);
DISPLAY 0.787234 (-2650 -1625);
FORCEPROP 1 LAST MATERIAL EMPTY
J 0
(-2750 -1500);
DISPLAY 0.787234 (-2750 -1500);
FORCEPROP 1 LAST PART_NUMBER CS00002JB13
J 0
(-2725 -1450);
DISPLAY 0.787234 (-2725 -1450);
FORCEPROP 1 LAST PATH I139
J 0
(-2550 -1400);
DISPLAY 0.978723 (-2550 -1400);
PAINT WHITE (-2550 -1400);
DISPLAY INVISIBLE (-2550 -1400);
FORCEPROP 2 LAST CDS_LIB pure_quanta
J 0
(-2500 -1550);
DISPLAY INVISIBLE (-2500 -1550);
FORCEPROP 1 LAST WATTAGE 1/16W
J 2
(-2575 -1625);
DISPLAY 0.787234 (-2575 -1625);
DISPLAY INVISIBLE (-2575 -1625);
FORCEPROP 1 LAST $LOCATION R869
J 0
(-2550 -1500);
DISPLAY 0.787234 (-2550 -1500);
FORCEPROP 1 LASTPIN (-2600 -1550) $PN 1
J 0
(-2588 -1538);
DISPLAY 0.787234 (-2588 -1538);
PAINT MONO (-2588 -1538);
FORCEPROP 1 LASTPIN (-2400 -1550) $PN 2
J 0
(-2438 -1538);
DISPLAY 0.787234 (-2438 -1538);
PAINT MONO (-2438 -1538);
FORCEPROP 0 LAST CDS_LOCATION R869
J 0
(-2725 -1400);
DISPLAY 0.680851 (-2725 -1400);
DISPLAY INVISIBLE (-2725 -1400);
FORCEPROP 0 LAST $SEC 1
J 0
(-2725 -1400);
DISPLAY 0.680851 (-2725 -1400);
PAINT MONO (-2725 -1400);
DISPLAY INVISIBLE (-2725 -1400);
FORCEPROP 0 LAST CDS_SEC 1
J 0
(-2725 -1400);
DISPLAY 0.680851 (-2725 -1400);
DISPLAY INVISIBLE (-2725 -1400);
FORCEADD OFFPAGE..4
R 2
(-3500 -1550);
FORCEPROP 2 LAST $XR0 54 
J 0
(-3721 -1550);
DISPLAY 0.638298 (-3721 -1550);
PAINT MONO (-3721 -1550);
FORCEPROP 2 LAST PATH I140
J 0
(-3700 -1500);
DISPLAY 0.680851 (-3700 -1500);
DISPLAY INVISIBLE (-3700 -1500);
FORCEPROP 2 LAST CDS_LIB standard
J 0
(-3500 -1550);
DISPLAY INVISIBLE (-3500 -1550);
FORCEPROP 1 LAST OFFPAGE TRUE
J 2
(-3825 -1675);
DISPLAY 0.872340 (-3825 -1675);
PAINT GREEN (-3825 -1675);
DISPLAY INVISIBLE (-3825 -1675);
FORCEPROP 1 LAST COMMENT_BODY TRUE
J 2
(-3475 -1650);
DISPLAY 0.872340 (-3475 -1650);
PAINT PEACH (-3475 -1650);
DISPLAY INVISIBLE (-3475 -1650);
FORCEADD Q_RES..1
(400 -1525);
FORCEPROP 1 LAST VALUE 0
J 2
(525 -1525);
DISPLAY 0.510638 (525 -1525);
PAINT SKYBLUE (525 -1525);
FORCEPROP 1 LAST PACK_TYPE 0402LF
J 0
(325 -1575);
DISPLAY 0.510638 (325 -1575);
PAINT SKYBLUE (325 -1575);
FORCEPROP 1 LAST MATERIAL EMPTY
J 0
(550 -1525);
DISPLAY 0.510638 (550 -1525);
PAINT RED (550 -1525);
FORCEPROP 1 LAST PART_NUMBER CS00002JB13
J 0
(300 -1475);
DISPLAY 0.510638 (300 -1475);
PAINT WHITE (300 -1475);
FORCEPROP 2 LAST CDS_LIB pure_quanta
J 0
(400 -1525);
DISPLAY INVISIBLE (400 -1525);
FORCEPROP 1 LAST PATH I141
J 0
(350 -1375);
DISPLAY 0.978723 (350 -1375);
PAINT WHITE (350 -1375);
DISPLAY INVISIBLE (350 -1375);
FORCEPROP 1 LAST TOLERANCE 5%
J 0
(400 -1625);
DISPLAY 0.510638 (400 -1625);
PAINT SKYBLUE (400 -1625);
DISPLAY INVISIBLE (400 -1625);
FORCEPROP 1 LAST WATTAGE 1/16W
J 2
(375 -1675);
DISPLAY 0.510638 (375 -1675);
PAINT SKYBLUE (375 -1675);
DISPLAY INVISIBLE (375 -1675);
FORCEPROP 1 LAST $LOCATION R872
J 0
(225 -1525);
DISPLAY 0.702128 (225 -1525);
PAINT YELLOW (225 -1525);
FORCEPROP 1 LASTPIN (300 -1525) $PN 1
J 0
(312 -1513);
DISPLAY 0.787234 (312 -1513);
PAINT MONO (312 -1513);
FORCEPROP 1 LASTPIN (500 -1525) $PN 2
J 0
(462 -1513);
DISPLAY 0.787234 (462 -1513);
PAINT MONO (462 -1513);
FORCEPROP 0 LAST CDS_LOCATION R872
J 0
(300 -1450);
DISPLAY 0.680851 (300 -1450);
DISPLAY INVISIBLE (300 -1450);
FORCEPROP 0 LAST $SEC 1
J 0
(300 -1450);
DISPLAY 0.680851 (300 -1450);
PAINT MONO (300 -1450);
DISPLAY INVISIBLE (300 -1450);
FORCEPROP 0 LAST CDS_SEC 1
J 0
(300 -1450);
DISPLAY 0.680851 (300 -1450);
DISPLAY INVISIBLE (300 -1450);
FORCEADD OFFPAGE..5
R 2
(1375 -1525);
FORCEPROP 2 LAST $XR0 55 
J 0
(1564 -1525);
DISPLAY 0.638298 (1564 -1525);
PAINT MONO (1564 -1525);
FORCEPROP 2 LAST CDS_LIB standard
J 0
(1375 -1525);
DISPLAY INVISIBLE (1375 -1525);
FORCEPROP 1 LAST OFFPAGE TRUE
J 2
(1050 -1650);
DISPLAY 0.872340 (1050 -1650);
PAINT GREEN (1050 -1650);
DISPLAY INVISIBLE (1050 -1650);
FORCEPROP 1 LAST COMMENT_BODY TRUE
J 2
(1275 -1600);
DISPLAY 0.872340 (1275 -1600);
PAINT PEACH (1275 -1600);
DISPLAY INVISIBLE (1275 -1600);
FORCEPROP 2 LAST PATH I142
J 0
(1750 -1475);
DISPLAY 0.680851 (1750 -1475);
DISPLAY INVISIBLE (1750 -1475);
FORCEADD UNIVERSAL_POWER..1
(2250 3325);
FORCEPROP 3 LASTPIN (2250 3275) SIG_NAME P3V3_LDO\g
J 0
(2260 3285);
DISPLAY 0.659574 (2260 3285);
PAINT MONO (2260 3285);
DISPLAY INVISIBLE (2260 3285);
FORCEPROP 1 LAST HDL_POWER P3V3_LDO
J 1
(2250 3375);
DISPLAY 0.702128 (2250 3375);
PAINT GREEN (2250 3375);
FORCEPROP 1 LAST PATH I143
J 0
(2300 3350);
DISPLAY 0.872340 (2300 3350);
PAINT AQUA (2300 3350);
DISPLAY INVISIBLE (2300 3350);
FORCEPROP 2 LAST CDS_LIB logical_power
J 0
(2250 3325);
DISPLAY INVISIBLE (2250 3325);
FORCEADD UNIVERSAL_POWER..1
(3900 -725);
FORCEPROP 3 LASTPIN (3900 -775) SIG_NAME P3V3_LDO\g
J 0
(3910 -765);
DISPLAY 0.659574 (3910 -765);
PAINT MONO (3910 -765);
DISPLAY INVISIBLE (3910 -765);
FORCEPROP 1 LAST HDL_POWER P3V3_LDO
J 1
(3900 -675);
DISPLAY 0.702128 (3900 -675);
PAINT GREEN (3900 -675);
FORCEPROP 1 LAST PATH I144
J 0
(3950 -700);
DISPLAY 0.872340 (3950 -700);
PAINT AQUA (3950 -700);
DISPLAY INVISIBLE (3950 -700);
FORCEPROP 2 LAST CDS_LIB logical_power
J 0
(3900 -725);
DISPLAY INVISIBLE (3900 -725);
FORCEADD Q_RES..1
(-625 -1700);
FORCEPROP 1 LAST VALUE 2.2K
J 2
(-750 -1700);
DISPLAY 0.510638 (-750 -1700);
PAINT SKYBLUE (-750 -1700);
FORCEPROP 1 LAST MATERIAL CHIP
J 0
(-575 -1700);
DISPLAY 0.510638 (-575 -1700);
PAINT SKYBLUE (-575 -1700);
FORCEPROP 1 LAST PACK_TYPE 0402LF
J 0
(-375 -1850);
DISPLAY 0.510638 (-375 -1850);
PAINT SKYBLUE (-375 -1850);
DISPLAY INVISIBLE (-375 -1850);
FORCEPROP 1 LAST WATTAGE 1/16W
J 2
(-650 -1850);
DISPLAY 0.510638 (-650 -1850);
PAINT SKYBLUE (-650 -1850);
DISPLAY INVISIBLE (-650 -1850);
FORCEPROP 1 LAST PART_NUMBER CS22202JB07
J 0
(-675 -1600);
DISPLAY 0.510638 (-675 -1600);
PAINT WHITE (-675 -1600);
DISPLAY INVISIBLE (-675 -1600);
FORCEPROP 1 LAST TOLERANCE 5%
J 0
(-625 -1800);
DISPLAY 0.510638 (-625 -1800);
PAINT SKYBLUE (-625 -1800);
DISPLAY INVISIBLE (-625 -1800);
FORCEPROP 1 LAST PATH I145
J 0
(-675 -1550);
DISPLAY 0.978723 (-675 -1550);
PAINT WHITE (-675 -1550);
DISPLAY INVISIBLE (-675 -1550);
FORCEPROP 2 LAST CDS_LIB pure_quanta
J 0
(-625 -1700);
DISPLAY INVISIBLE (-625 -1700);
FORCEPROP 1 LAST LOCATION R709
J 0
(-800 -1675);
DISPLAY 0.702128 (-800 -1675);
PAINT YELLOW (-800 -1675);
FORCEPROP 1 LASTPIN (-725 -1700) $PN 1
J 0
(-713 -1688);
DISPLAY 0.787234 (-713 -1688);
PAINT MONO (-713 -1688);
FORCEPROP 1 LASTPIN (-525 -1700) $PN 2
J 0
(-563 -1688);
DISPLAY 0.787234 (-563 -1688);
PAINT MONO (-563 -1688);
FORCEPROP 0 LAST $SEC 1
J 0
(-800 -1625);
PAINT MONO (-800 -1625);
DISPLAY INVISIBLE (-800 -1625);
FORCEPROP 0 LAST CDS_SEC 1
J 0
(-800 -1625);
PAINT MONO (-800 -1625);
DISPLAY INVISIBLE (-800 -1625);
FORCEADD Q_RES..1
(850 1625);
FORCEPROP 1 LAST MATERIAL CHIP
J 0
(700 1500);
DISPLAY 0.787234 (700 1500);
FORCEPROP 1 LAST VALUE 2.2
J 2
(850 1550);
DISPLAY 0.787234 (850 1550);
FORCEPROP 1 LAST PACK_TYPE 0402LF
J 0
(875 1500);
DISPLAY 0.787234 (875 1500);
FORCEPROP 1 LAST TOLERANCE 1%
J 0
(875 1550);
DISPLAY 0.787234 (875 1550);
FORCEPROP 1 LAST PART_NUMBER CS-2202FB01
J 0
(800 1725);
DISPLAY 0.787234 (800 1725);
FORCEPROP 1 LAST WATTAGE 1/16W
J 2
(800 1500);
DISPLAY 0.787234 (800 1500);
DISPLAY INVISIBLE (800 1500);
FORCEPROP 2 LAST CDS_LIB pure_quanta
J 0
(850 1625);
DISPLAY INVISIBLE (850 1625);
FORCEPROP 1 LAST PATH I146
J 0
(800 1775);
DISPLAY 0.978723 (800 1775);
PAINT WHITE (800 1775);
DISPLAY INVISIBLE (800 1775);
FORCEPROP 1 LAST LOCATION R415
J 0
(800 1675);
DISPLAY 0.787234 (800 1675);
FORCEPROP 1 LASTPIN (750 1625) $PN 1
J 0
(762 1637);
DISPLAY 0.787234 (762 1637);
PAINT MONO (762 1637);
FORCEPROP 1 LASTPIN (950 1625) $PN 2
J 0
(912 1637);
DISPLAY 0.787234 (912 1637);
PAINT MONO (912 1637);
FORCEPROP 0 LAST $SEC 1
J 0
(800 1775);
DISPLAY 0.680851 (800 1775);
PAINT MONO (800 1775);
DISPLAY INVISIBLE (800 1775);
FORCEPROP 0 LAST CDS_SEC 1
J 0
(800 1775);
DISPLAY 0.680851 (800 1775);
DISPLAY INVISIBLE (800 1775);
FORCEADD Q_RES..1
(-2500 -1800);
FORCEPROP 1 LAST PART_NUMBER CS11002FB07
J 0
(-2750 -1850);
DISPLAY 0.510638 (-2750 -1850);
PAINT WHITE (-2750 -1850);
FORCEPROP 1 LAST MATERIAL CHIP
J 0
(-2825 -1900);
DISPLAY 0.510638 (-2825 -1900);
PAINT SKYBLUE (-2825 -1900);
FORCEPROP 1 LAST PACK_TYPE 0402LF
J 0
(-2675 -1900);
DISPLAY 0.510638 (-2675 -1900);
PAINT SKYBLUE (-2675 -1900);
FORCEPROP 1 LAST WATTAGE 1/16W
J 2
(-2850 -1900);
DISPLAY 0.510638 (-2850 -1900);
PAINT SKYBLUE (-2850 -1900);
FORCEPROP 1 LAST TOLERANCE 1%
J 0
(-2475 -1900);
DISPLAY 0.510638 (-2475 -1900);
PAINT SKYBLUE (-2475 -1900);
FORCEPROP 1 LAST VALUE 100
J 0
(-2400 -1800);
DISPLAY 0.510638 (-2400 -1800);
PAINT SKYBLUE (-2400 -1800);
FORCEPROP 2 LAST CDS_LIB pure_quanta
J 0
(-2500 -1800);
DISPLAY INVISIBLE (-2500 -1800);
FORCEPROP 1 LAST PATH I147
J 0
(-2550 -1650);
DISPLAY 0.978723 (-2550 -1650);
PAINT WHITE (-2550 -1650);
DISPLAY INVISIBLE (-2550 -1650);
FORCEPROP 1 LAST LOCATION R380
J 0
(-2700 -1800);
DISPLAY 0.702128 (-2700 -1800);
PAINT YELLOW (-2700 -1800);
FORCEPROP 1 LASTPIN (-2600 -1800) $PN 1
J 0
(-2588 -1788);
DISPLAY 0.787234 (-2588 -1788);
PAINT MONO (-2588 -1788);
FORCEPROP 1 LASTPIN (-2400 -1800) $PN 2
J 0
(-2438 -1788);
DISPLAY 0.787234 (-2438 -1788);
PAINT MONO (-2438 -1788);
FORCEPROP 0 LAST $SEC 1
J 0
(-2700 -1750);
PAINT MONO (-2700 -1750);
DISPLAY INVISIBLE (-2700 -1750);
FORCEPROP 0 LAST CDS_SEC 1
J 0
(-2700 -1750);
PAINT MONO (-2700 -1750);
DISPLAY INVISIBLE (-2700 -1750);
FORCEADD Q_CAP..1
(1350 1475);
FORCEPROP 1 LAST TOLERANCE 10%
J 0
(1425 1500);
DISPLAY 0.510638 (1425 1500);
PAINT SKYBLUE (1425 1500);
FORCEPROP 1 LAST MATERIAL X7R
J 0
(1425 1450);
DISPLAY 0.510638 (1425 1450);
PAINT SKYBLUE (1425 1450);
FORCEPROP 1 LAST PACK_TYPE 0402
J 0
(1425 1350);
DISPLAY 0.510638 (1425 1350);
PAINT SKYBLUE (1425 1350);
FORCEPROP 1 LAST PART_NUMBER CH4223K1B00
J 0
(1425 1400);
DISPLAY 0.510638 (1425 1400);
PAINT WHITE (1425 1400);
FORCEPROP 1 LAST VOLTAGE 16V
J 0
(1425 1550);
DISPLAY 0.510638 (1425 1550);
PAINT SKYBLUE (1425 1550);
FORCEPROP 1 LAST VALUE 0.22UF
J 0
(1425 1600);
DISPLAY 0.510638 (1425 1600);
PAINT SKYBLUE (1425 1600);
FORCEPROP 2 LAST CDS_LIB pure_quanta
J 0
(1350 1475);
DISPLAY INVISIBLE (1350 1475);
FORCEPROP 2 LAST SEC_TYPE 0402
J 0
(1400 1675);
DISPLAY 1.021277 (1400 1675);
DISPLAY INVISIBLE (1400 1675);
FORCEPROP 1 LAST PATH I15
J 0
(1400 1625);
DISPLAY 0.978723 (1400 1625);
PAINT WHITE (1400 1625);
DISPLAY INVISIBLE (1400 1625);
FORCEPROP 1 LAST LOCATION PC224
J 0
(1425 1650);
DISPLAY 0.702128 (1425 1650);
PAINT AQUA (1425 1650);
FORCEPROP 1 LASTPIN (1350 1575) $PN 1
J 0
(1360 1555);
DISPLAY 0.808511 (1360 1555);
PAINT WHITE (1360 1555);
FORCEPROP 1 LASTPIN (1350 1375) $PN 2
J 0
(1360 1355);
DISPLAY 0.808511 (1360 1355);
PAINT WHITE (1360 1355);
FORCEPROP 2 LAST SEC 1
J 0
(1400 1675);
DISPLAY 0.680851 (1400 1675);
PAINT MONO (1400 1675);
DISPLAY INVISIBLE (1400 1675);
FORCEADD Q_RES..2
R 6
(1300 75);
FORCEPROP 1 LAST PART_NUMBER CS31242FB02
J 0
(1340 200);
DISPLAY 0.510638 (1340 200);
PAINT WHITE (1340 200);
FORCEPROP 1 LAST MATERIAL CHIP
J 0
(1340 150);
DISPLAY 0.510638 (1340 150);
PAINT SKYBLUE (1340 150);
FORCEPROP 1 LAST PACK_TYPE 0402LF
J 0
(1340 250);
DISPLAY 0.510638 (1340 250);
PAINT SKYBLUE (1340 250);
FORCEPROP 1 LAST TOLERANCE 1%
J 0
(1345 50);
DISPLAY 0.510638 (1345 50);
PAINT SKYBLUE (1345 50);
FORCEPROP 1 LAST WATTAGE 1/16W
J 0
(1340 100);
DISPLAY 0.510638 (1340 100);
PAINT SKYBLUE (1340 100);
FORCEPROP 1 LAST VALUE 12.4K
J 0
(1345 0);
DISPLAY 0.510638 (1345 0);
PAINT SKYBLUE (1345 0);
FORCEPROP 2 LAST CDS_LIB pure_quanta
J 0
(1300 75);
DISPLAY INVISIBLE (1300 75);
FORCEPROP 1 LAST PATH I17
J 0
(1350 -100);
DISPLAY 0.978723 (1350 -100);
PAINT WHITE (1350 -100);
DISPLAY INVISIBLE (1350 -100);
FORCEPROP 1 LAST LOCATION PR530
J 0
(1345 -50);
DISPLAY 0.702128 (1345 -50);
PAINT AQUA (1345 -50);
FORCEPROP 0 LAST $SEC 1
J 0
(1350 275);
DISPLAY 0.680851 (1350 275);
PAINT MONO (1350 275);
DISPLAY INVISIBLE (1350 275);
FORCEPROP 0 LAST CDS_SEC 1
J 0
(1350 275);
DISPLAY 1.021277 (1350 275);
DISPLAY INVISIBLE (1350 275);
FORCEPROP 1 LASTPIN (1300 -25) $PN 1
J 0
(1305 13);
DISPLAY 0.808511 (1305 13);
PAINT WHITE (1305 13);
DISPLAY INVISIBLE (1305 13);
FORCEPROP 1 LASTPIN (1300 175) $PN 2
J 0
(1305 165);
DISPLAY 0.808511 (1305 165);
PAINT WHITE (1305 165);
DISPLAY INVISIBLE (1305 165);
FORCEADD UNIVERSAL_GND..1
(1300 -200);
FORCEPROP 3 LASTPIN (1300 -150) SIG_NAME GND\g
J 0
(1310 -140);
DISPLAY 0.659574 (1310 -140);
PAINT MONO (1310 -140);
DISPLAY INVISIBLE (1310 -140);
FORCEPROP 1 LAST HDL_POWER GND
J 1
(1325 -275);
DISPLAY 0.702128 (1325 -275);
PAINT GREEN (1325 -275);
DISPLAY INVISIBLE (1325 -275);
FORCEPROP 1 LAST PATH I18
J 0
(1375 -200);
DISPLAY 0.872340 (1375 -200);
PAINT AQUA (1375 -200);
DISPLAY INVISIBLE (1375 -200);
FORCEPROP 2 LAST CDS_LIB logical_power
J 0
(1300 -200);
DISPLAY INVISIBLE (1300 -200);
FORCEADD VCCAUX15..1
(-3375 2650);
FORCEPROP 3 LASTPIN (-3375 2600) SIG_NAME P12V_AUX\g
J 0
(-3365 2610);
DISPLAY 0.659574 (-3365 2610);
PAINT MONO (-3365 2610);
DISPLAY INVISIBLE (-3365 2610);
FORCEPROP 1 LAST HDL_POWER P12V_AUX
J 1
(-3375 2700);
DISPLAY 0.702128 (-3375 2700);
PAINT GREEN (-3375 2700);
FORCEPROP 2 LAST CDS_LIB logical_power
J 0
(-3375 2650);
DISPLAY INVISIBLE (-3375 2650);
FORCEPROP 1 LAST PATH I2
J 0
(-3325 2675);
DISPLAY 0.872340 (-3325 2675);
PAINT AQUA (-3325 2675);
DISPLAY INVISIBLE (-3325 2675);
FORCEADD Q_CAP..1
(3175 1075);
FORCEPROP 1 LAST TOLERANCE 10%
J 0
(3225 1025);
DISPLAY 0.510638 (3225 1025);
PAINT SKYBLUE (3225 1025);
FORCEPROP 1 LAST MATERIAL X7R
J 0
(3225 975);
DISPLAY 0.510638 (3225 975);
PAINT SKYBLUE (3225 975);
FORCEPROP 1 LAST VOLTAGE 25V
J 0
(3225 1075);
DISPLAY 0.510638 (3225 1075);
PAINT SKYBLUE (3225 1075);
FORCEPROP 1 LAST VALUE 0.1UF
J 0
(3225 1125);
DISPLAY 0.510638 (3225 1125);
PAINT SKYBLUE (3225 1125);
FORCEPROP 1 LAST PART_NUMBER CH4104K1B00
J 0
(3225 925);
DISPLAY 0.510638 (3225 925);
PAINT WHITE (3225 925);
FORCEPROP 1 LAST PACK_TYPE 0402
J 0
(3225 875);
DISPLAY 0.510638 (3225 875);
PAINT SKYBLUE (3225 875);
FORCEPROP 2 LAST SEC_TYPE 0402
J 0
(3225 1275);
DISPLAY 1.021277 (3225 1275);
DISPLAY INVISIBLE (3225 1275);
FORCEPROP 2 LAST CDS_LIB pure_quanta
J 0
(3175 1075);
DISPLAY INVISIBLE (3175 1075);
FORCEPROP 1 LAST PATH I23
J 0
(3225 1225);
DISPLAY 0.978723 (3225 1225);
PAINT WHITE (3225 1225);
DISPLAY INVISIBLE (3225 1225);
FORCEPROP 1 LAST LOCATION PC225
J 0
(3225 1175);
DISPLAY 0.702128 (3225 1175);
PAINT AQUA (3225 1175);
FORCEPROP 1 LASTPIN (3175 1175) $PN 1
J 0
(3185 1155);
DISPLAY 0.808511 (3185 1155);
PAINT WHITE (3185 1155);
FORCEPROP 1 LASTPIN (3175 975) $PN 2
J 0
(3185 955);
DISPLAY 0.808511 (3185 955);
PAINT WHITE (3185 955);
FORCEPROP 2 LAST SEC 1
J 0
(3225 1275);
DISPLAY 0.680851 (3225 1275);
PAINT MONO (3225 1275);
DISPLAY INVISIBLE (3225 1275);
FORCEADD Q_RES..1
R 6
(3200 475);
FORCEPROP 1 LAST PART_NUMBER CS35602FB00
J 0
(3150 375);
DISPLAY 0.510638 (3150 375);
PAINT WHITE (3150 375);
FORCEPROP 1 LAST VALUE 56K
J 2
(3175 575);
DISPLAY 0.510638 (3175 575);
PAINT SKYBLUE (3175 575);
FORCEPROP 1 LAST WATTAGE 1/16W
J 2
(3175 625);
DISPLAY 0.510638 (3175 625);
PAINT SKYBLUE (3175 625);
FORCEPROP 1 LAST MATERIAL CHIP
J 0
(3200 625);
DISPLAY 0.510638 (3200 625);
PAINT SKYBLUE (3200 625);
FORCEPROP 1 LAST TOLERANCE 1%
J 0
(3200 575);
DISPLAY 0.510638 (3200 575);
PAINT SKYBLUE (3200 575);
FORCEPROP 1 LAST PACK_TYPE 0402LF
J 0
(3450 625);
DISPLAY 0.510638 (3450 625);
PAINT SKYBLUE (3450 625);
FORCEPROP 2 LAST CDS_LIB pure_quanta
J 0
(3200 475);
DISPLAY INVISIBLE (3200 475);
FORCEPROP 1 LAST PATH I25
J 0
(3150 325);
DISPLAY 0.978723 (3150 325);
PAINT WHITE (3150 325);
DISPLAY INVISIBLE (3150 325);
FORCEPROP 1 LAST LOCATION PR534
J 0
(3025 300);
DISPLAY 0.702128 (3025 300);
PAINT AQUA (3025 300);
FORCEPROP 0 LAST $SEC 1
J 0
(3450 650);
DISPLAY 0.680851 (3450 650);
PAINT MONO (3450 650);
DISPLAY INVISIBLE (3450 650);
FORCEPROP 0 LAST CDS_SEC 1
J 0
(3450 650);
DISPLAY 1.021277 (3450 650);
DISPLAY INVISIBLE (3450 650);
FORCEPROP 1 LASTPIN (3100 475) $PN 1
J 0
(3112 463);
DISPLAY 0.808511 (3112 463);
PAINT WHITE (3112 463);
DISPLAY INVISIBLE (3112 463);
FORCEPROP 1 LASTPIN (3300 475) $PN 2
J 0
(3262 463);
DISPLAY 0.808511 (3262 463);
PAINT WHITE (3262 463);
DISPLAY INVISIBLE (3262 463);
FORCEADD UNIVERSAL_GND..1
(4475 750);
FORCEPROP 3 LASTPIN (4475 800) SIG_NAME GND\g
J 0
(4485 810);
DISPLAY 0.659574 (4485 810);
PAINT MONO (4485 810);
DISPLAY INVISIBLE (4485 810);
FORCEPROP 2 LAST CDS_LIB logical_power
J 0
(4475 750);
DISPLAY INVISIBLE (4475 750);
FORCEPROP 1 LAST HDL_POWER GND
J 1
(4500 675);
DISPLAY 0.702128 (4500 675);
PAINT GREEN (4500 675);
DISPLAY INVISIBLE (4500 675);
FORCEPROP 1 LAST PATH I28
J 0
(4550 750);
DISPLAY 0.872340 (4550 750);
PAINT AQUA (4550 750);
DISPLAY INVISIBLE (4550 750);
FORCEADD VCCAUX15..1
(5125 1450);
FORCEPROP 3 LASTPIN (5125 1400) SIG_NAME P3V3_AUX\g
J 0
(5135 1410);
DISPLAY 0.659574 (5135 1410);
PAINT MONO (5135 1410);
DISPLAY INVISIBLE (5135 1410);
FORCEPROP 1 LAST HDL_POWER P3V3_AUX
J 1
(5125 1500);
DISPLAY 0.702128 (5125 1500);
PAINT GREEN (5125 1500);
FORCEPROP 2 LAST CDS_LIB logical_power
J 0
(5125 1450);
DISPLAY INVISIBLE (5125 1450);
FORCEPROP 1 LAST PATH I31
J 0
(5175 1475);
DISPLAY 0.872340 (5175 1475);
PAINT AQUA (5175 1475);
DISPLAY INVISIBLE (5175 1475);
FORCEADD Q_INDUCTOR..1
(-2925 2325);
FORCEPROP 1 LAST PART_NUMBER CX220TN1001
J 0
(-3125 2250);
DISPLAY 0.510638 (-3125 2250);
PAINT WHITE (-3125 2250);
FORCEPROP 2 LAST PACK_TYPE SMLF
J 0
(-3000 2075);
DISPLAY 0.510638 (-3000 2075);
PAINT SKYBLUE (-3000 2075);
FORCEPROP 1 LAST MATERIAL IND
J 0
(-3025 2200);
DISPLAY 0.510638 (-3025 2200);
PAINT SKYBLUE (-3025 2200);
FORCEPROP 2 LAST VALUE BLM18SN220TN1D/8000MA
J 0
(-3275 2150);
DISPLAY 0.510638 (-3275 2150);
PAINT SKYBLUE (-3275 2150);
FORCEPROP 1 LAST NEEDS_NO_SIZE TRUE
J 0
(-2925 2325);
DISPLAY 0.468085 (-2925 2325);
PAINT GREEN (-2925 2325);
DISPLAY INVISIBLE (-2925 2325);
FORCEPROP 2 LAST CDS_LIB pure_quanta
J 0
(-2925 2325);
DISPLAY INVISIBLE (-2925 2325);
FORCEPROP 1 LAST PATH I32
J 0
(-2850 2380);
DISPLAY 0.723404 (-2850 2380);
PAINT GREEN (-2850 2380);
DISPLAY INVISIBLE (-2850 2380);
FORCEPROP 1 LAST LOCATION PL19
J 0
(-3025 2375);
DISPLAY 0.702128 (-3025 2375);
PAINT AQUA (-3025 2375);
FORCEPROP 0 LASTPIN (-3025 2300) $PN 1
J 2
(-3035 2310);
DISPLAY 0.808511 (-3035 2310);
PAINT WHITE (-3035 2310);
FORCEPROP 0 LASTPIN (-2825 2300) $PN 2
J 0
(-2815 2310);
DISPLAY 0.808511 (-2815 2310);
PAINT WHITE (-2815 2310);
FORCEPROP 0 LAST $SEC 1
J 0
(-3025 2425);
DISPLAY 0.680851 (-3025 2425);
PAINT MONO (-3025 2425);
DISPLAY INVISIBLE (-3025 2425);
FORCEPROP 0 LAST CDS_SEC 1
J 0
(-3025 2425);
DISPLAY 1.021277 (-3025 2425);
DISPLAY INVISIBLE (-3025 2425);
FORCEADD Q_CAP..1
(3650 1075);
FORCEPROP 1 LAST PACK_TYPE C0805
J 0
(3700 875);
DISPLAY 0.510638 (3700 875);
PAINT SKYBLUE (3700 875);
FORCEPROP 1 LAST VALUE 22UF
J 0
(3700 1125);
DISPLAY 0.510638 (3700 1125);
PAINT SKYBLUE (3700 1125);
FORCEPROP 1 LAST PART_NUMBER CH6222MEA00
J 0
(3700 925);
DISPLAY 0.510638 (3700 925);
PAINT WHITE (3700 925);
FORCEPROP 1 LAST MATERIAL X6S
J 0
(3700 975);
DISPLAY 0.510638 (3700 975);
PAINT SKYBLUE (3700 975);
FORCEPROP 1 LAST VOLTAGE 10V
J 0
(3700 1075);
DISPLAY 0.510638 (3700 1075);
PAINT SKYBLUE (3700 1075);
FORCEPROP 1 LAST TOLERANCE 20%
J 0
(3700 1025);
DISPLAY 0.510638 (3700 1025);
PAINT SKYBLUE (3700 1025);
FORCEPROP 2 LAST CDS_LIB pure_quanta
J 0
(3650 1075);
DISPLAY INVISIBLE (3650 1075);
FORCEPROP 1 LAST PATH I35
J 0
(3700 1225);
DISPLAY 0.978723 (3700 1225);
PAINT WHITE (3700 1225);
DISPLAY INVISIBLE (3700 1225);
FORCEPROP 1 LAST LOCATION PC226
J 0
(3700 1175);
DISPLAY 0.702128 (3700 1175);
PAINT AQUA (3700 1175);
FORCEPROP 1 LASTPIN (3650 1175) $PN 1
J 0
(3660 1155);
DISPLAY 0.808511 (3660 1155);
PAINT WHITE (3660 1155);
FORCEPROP 1 LASTPIN (3650 975) $PN 2
J 0
(3660 955);
DISPLAY 0.808511 (3660 955);
PAINT WHITE (3660 955);
FORCEPROP 0 LAST $SEC 1
J 0
(3700 1225);
DISPLAY INVISIBLE (3700 1225);
FORCEPROP 0 LAST CDS_SEC 1
J 0
(3700 1225);
DISPLAY INVISIBLE (3700 1225);
FORCEADD Q_CAP..1
(4000 1075);
FORCEPROP 1 LAST PART_NUMBER CH6222MEA00
J 0
(4050 925);
DISPLAY 0.510638 (4050 925);
PAINT WHITE (4050 925);
FORCEPROP 1 LAST MATERIAL X6S
J 0
(4050 975);
DISPLAY 0.510638 (4050 975);
PAINT SKYBLUE (4050 975);
FORCEPROP 1 LAST VOLTAGE 10V
J 0
(4050 1075);
DISPLAY 0.510638 (4050 1075);
PAINT SKYBLUE (4050 1075);
FORCEPROP 1 LAST PACK_TYPE C0805
J 0
(4050 875);
DISPLAY 0.510638 (4050 875);
PAINT SKYBLUE (4050 875);
FORCEPROP 1 LAST VALUE 22UF
J 0
(4050 1125);
DISPLAY 0.510638 (4050 1125);
PAINT SKYBLUE (4050 1125);
FORCEPROP 1 LAST TOLERANCE 20%
J 0
(4050 1025);
DISPLAY 0.510638 (4050 1025);
PAINT SKYBLUE (4050 1025);
FORCEPROP 2 LAST CDS_LIB pure_quanta
J 0
(4000 1075);
DISPLAY INVISIBLE (4000 1075);
FORCEPROP 1 LAST PATH I36
J 0
(4050 1225);
DISPLAY 0.978723 (4050 1225);
PAINT WHITE (4050 1225);
DISPLAY INVISIBLE (4050 1225);
FORCEPROP 1 LAST LOCATION PC227
J 0
(4050 1175);
DISPLAY 0.702128 (4050 1175);
PAINT AQUA (4050 1175);
FORCEPROP 1 LASTPIN (4000 1175) $PN 1
J 0
(4010 1155);
DISPLAY 0.808511 (4010 1155);
PAINT WHITE (4010 1155);
FORCEPROP 1 LASTPIN (4000 975) $PN 2
J 0
(4010 955);
DISPLAY 0.808511 (4010 955);
PAINT WHITE (4010 955);
FORCEPROP 0 LAST $SEC 1
J 0
(4050 1225);
DISPLAY INVISIBLE (4050 1225);
FORCEPROP 0 LAST CDS_SEC 1
J 0
(4050 1225);
DISPLAY INVISIBLE (4050 1225);
FORCEADD Q_CAP..1
(4325 1075);
FORCEPROP 1 LAST PACK_TYPE C0805
J 0
(4375 875);
DISPLAY 0.510638 (4375 875);
PAINT SKYBLUE (4375 875);
FORCEPROP 1 LAST PART_NUMBER CH6222MEA00
J 0
(4375 925);
DISPLAY 0.510638 (4375 925);
PAINT WHITE (4375 925);
FORCEPROP 1 LAST VALUE 22UF
J 0
(4375 1125);
DISPLAY 0.510638 (4375 1125);
PAINT SKYBLUE (4375 1125);
FORCEPROP 1 LAST MATERIAL X6S
J 0
(4375 975);
DISPLAY 0.510638 (4375 975);
PAINT SKYBLUE (4375 975);
FORCEPROP 1 LAST VOLTAGE 10V
J 0
(4375 1075);
DISPLAY 0.510638 (4375 1075);
PAINT SKYBLUE (4375 1075);
FORCEPROP 1 LAST TOLERANCE 20%
J 0
(4375 1025);
DISPLAY 0.510638 (4375 1025);
PAINT SKYBLUE (4375 1025);
FORCEPROP 2 LAST CDS_LIB pure_quanta
J 0
(4325 1075);
DISPLAY INVISIBLE (4325 1075);
FORCEPROP 1 LAST PATH I37
J 0
(4375 1225);
DISPLAY 0.978723 (4375 1225);
PAINT WHITE (4375 1225);
DISPLAY INVISIBLE (4375 1225);
FORCEPROP 1 LAST LOCATION PC228
J 0
(4375 1175);
DISPLAY 0.702128 (4375 1175);
PAINT AQUA (4375 1175);
FORCEPROP 1 LASTPIN (4325 1175) $PN 1
J 0
(4335 1155);
DISPLAY 0.808511 (4335 1155);
PAINT WHITE (4335 1155);
FORCEPROP 1 LASTPIN (4325 975) $PN 2
J 0
(4335 955);
DISPLAY 0.808511 (4335 955);
PAINT WHITE (4335 955);
FORCEPROP 0 LAST $SEC 1
J 0
(4375 1225);
DISPLAY INVISIBLE (4375 1225);
FORCEPROP 0 LAST CDS_SEC 1
J 0
(4375 1225);
DISPLAY INVISIBLE (4375 1225);
FORCEADD Q_CAP..1
(4650 1075);
FORCEPROP 1 LAST PACK_TYPE C0805
J 0
(4700 875);
DISPLAY 0.510638 (4700 875);
PAINT SKYBLUE (4700 875);
FORCEPROP 1 LAST VALUE 22UF
J 0
(4700 1125);
DISPLAY 0.510638 (4700 1125);
PAINT SKYBLUE (4700 1125);
FORCEPROP 1 LAST PART_NUMBER CH6222MEA00
J 0
(4700 925);
DISPLAY 0.510638 (4700 925);
PAINT WHITE (4700 925);
FORCEPROP 1 LAST MATERIAL X6S
J 0
(4700 975);
DISPLAY 0.510638 (4700 975);
PAINT SKYBLUE (4700 975);
FORCEPROP 1 LAST VOLTAGE 10V
J 0
(4700 1075);
DISPLAY 0.510638 (4700 1075);
PAINT SKYBLUE (4700 1075);
FORCEPROP 1 LAST TOLERANCE 20%
J 0
(4700 1025);
DISPLAY 0.510638 (4700 1025);
PAINT SKYBLUE (4700 1025);
FORCEPROP 2 LAST CDS_LIB pure_quanta
J 0
(4650 1075);
DISPLAY INVISIBLE (4650 1075);
FORCEPROP 1 LAST PATH I38
J 0
(4700 1225);
DISPLAY 0.978723 (4700 1225);
PAINT WHITE (4700 1225);
DISPLAY INVISIBLE (4700 1225);
FORCEPROP 1 LAST LOCATION PC229
J 0
(4700 1175);
DISPLAY 0.702128 (4700 1175);
PAINT AQUA (4700 1175);
FORCEPROP 1 LASTPIN (4650 1175) $PN 1
J 0
(4660 1155);
DISPLAY 0.808511 (4660 1155);
PAINT WHITE (4660 1155);
FORCEPROP 1 LASTPIN (4650 975) $PN 2
J 0
(4660 955);
DISPLAY 0.808511 (4660 955);
PAINT WHITE (4660 955);
FORCEPROP 0 LAST $SEC 1
J 0
(4700 1225);
DISPLAY INVISIBLE (4700 1225);
FORCEPROP 0 LAST CDS_SEC 1
J 0
(4700 1225);
DISPLAY INVISIBLE (4700 1225);
FORCEADD UNIVERSAL_POWER..1
(325 2275);
FORCEPROP 3 LASTPIN (325 2225) SIG_NAME P3V3_AUX\g
J 0
(335 2235);
DISPLAY 0.659574 (335 2235);
PAINT MONO (335 2235);
DISPLAY INVISIBLE (335 2235);
FORCEPROP 1 LAST HDL_POWER P3V3_AUX
J 1
(325 2325);
DISPLAY 0.702128 (325 2325);
PAINT GREEN (325 2325);
FORCEPROP 2 LAST CDS_LIB logical_power
J 0
(325 2275);
DISPLAY INVISIBLE (325 2275);
FORCEPROP 1 LAST PATH I39
J 0
(375 2300);
DISPLAY 0.872340 (375 2300);
PAINT AQUA (375 2300);
DISPLAY INVISIBLE (375 2300);
FORCEADD UNIVERSAL_GND..1
(-1600 200);
FORCEPROP 3 LASTPIN (-1600 250) SIG_NAME GND\g
J 0
(-1590 260);
DISPLAY 0.659574 (-1590 260);
PAINT MONO (-1590 260);
DISPLAY INVISIBLE (-1590 260);
FORCEPROP 2 LAST CDS_LIB logical_power
J 0
(-1600 200);
DISPLAY INVISIBLE (-1600 200);
FORCEPROP 1 LAST HDL_POWER GND
J 1
(-1575 125);
DISPLAY 0.702128 (-1575 125);
PAINT GREEN (-1575 125);
DISPLAY INVISIBLE (-1575 125);
FORCEPROP 1 LAST PATH I4
J 0
(-1525 200);
DISPLAY 0.872340 (-1525 200);
PAINT AQUA (-1525 200);
DISPLAY INVISIBLE (-1525 200);
FORCEADD UNIVERSAL_GND..1
(-2125 1725);
FORCEPROP 3 LASTPIN (-2125 1775) SIG_NAME GND\g
J 0
(-2115 1785);
DISPLAY 0.659574 (-2115 1785);
PAINT MONO (-2115 1785);
DISPLAY INVISIBLE (-2115 1785);
FORCEPROP 2 LAST CDS_LIB logical_power
J 0
(-2125 1725);
DISPLAY INVISIBLE (-2125 1725);
FORCEPROP 1 LAST HDL_POWER GND
J 1
(-2100 1650);
DISPLAY 0.702128 (-2100 1650);
PAINT GREEN (-2100 1650);
DISPLAY INVISIBLE (-2100 1650);
FORCEPROP 1 LAST PATH I5
J 0
(-2050 1725);
DISPLAY 0.872340 (-2050 1725);
PAINT AQUA (-2050 1725);
DISPLAY INVISIBLE (-2050 1725);
FORCEADD OFFPAGE..5
R 2
(3825 1825);
FORCEPROP 2 LAST $XR1 53 
J 0
(4104 1825);
DISPLAY 0.638298 (4104 1825);
PAINT MONO (4104 1825);
FORCEPROP 2 LAST $XR0 35 
J 0
(4014 1825);
DISPLAY 0.638298 (4014 1825);
PAINT MONO (4014 1825);
FORCEPROP 1 LAST COMMENT_BODY TRUE
J 2
(3725 1750);
DISPLAY 0.872340 (3725 1750);
PAINT PEACH (3725 1750);
DISPLAY INVISIBLE (3725 1750);
FORCEPROP 1 LAST OFFPAGE TRUE
J 2
(3500 1700);
DISPLAY 0.872340 (3500 1700);
PAINT GREEN (3500 1700);
DISPLAY INVISIBLE (3500 1700);
FORCEPROP 2 LAST CDS_LIB standard
J 0
(3825 1825);
DISPLAY INVISIBLE (3825 1825);
FORCEPROP 2 LAST PATH I55
J 0
(4000 1900);
DISPLAY 1.021277 (4000 1900);
DISPLAY INVISIBLE (4000 1900);
FORCEADD UNIVERSAL_GND..1
(-875 -2250);
FORCEPROP 3 LASTPIN (-875 -2200) SIG_NAME GND\g
J 0
(-865 -2190);
DISPLAY 0.659574 (-865 -2190);
PAINT MONO (-865 -2190);
DISPLAY INVISIBLE (-865 -2190);
FORCEPROP 2 LAST CDS_LIB logical_power
J 0
(-875 -2250);
DISPLAY INVISIBLE (-875 -2250);
FORCEPROP 1 LAST HDL_POWER GND
J 1
(-850 -2325);
DISPLAY 0.702128 (-850 -2325);
PAINT GREEN (-850 -2325);
DISPLAY INVISIBLE (-850 -2325);
FORCEPROP 1 LAST PATH I62
J 0
(-800 -2250);
DISPLAY 0.872340 (-800 -2250);
PAINT AQUA (-800 -2250);
DISPLAY INVISIBLE (-800 -2250);
FORCEADD Q_CAP..1
(-1975 -1250);
FORCEPROP 1 LAST MATERIAL X7R
J 0
(-1925 -1350);
DISPLAY 0.510638 (-1925 -1350);
PAINT SKYBLUE (-1925 -1350);
FORCEPROP 1 LAST TOLERANCE 10%
J 0
(-1925 -1300);
DISPLAY 0.510638 (-1925 -1300);
PAINT SKYBLUE (-1925 -1300);
FORCEPROP 1 LAST VOLTAGE 25V
J 0
(-1925 -1250);
DISPLAY 0.510638 (-1925 -1250);
PAINT SKYBLUE (-1925 -1250);
FORCEPROP 1 LAST VALUE 0.1UF
J 0
(-1925 -1200);
DISPLAY 0.510638 (-1925 -1200);
PAINT SKYBLUE (-1925 -1200);
FORCEPROP 1 LAST PACK_TYPE 0402
J 0
(-1925 -1450);
DISPLAY 0.510638 (-1925 -1450);
PAINT SKYBLUE (-1925 -1450);
FORCEPROP 2 LAST CDS_LIB pure_quanta
J 0
(-1975 -1250);
DISPLAY INVISIBLE (-1975 -1250);
FORCEPROP 1 LAST PART_NUMBER CH4104K1B00
J 0
(-1925 -1400);
DISPLAY 0.510638 (-1925 -1400);
PAINT WHITE (-1925 -1400);
DISPLAY INVISIBLE (-1925 -1400);
FORCEPROP 1 LAST PATH I63
J 0
(-1925 -1100);
DISPLAY 0.978723 (-1925 -1100);
PAINT WHITE (-1925 -1100);
DISPLAY INVISIBLE (-1925 -1100);
FORCEPROP 1 LAST LOCATION C240
J 0
(-1925 -1150);
DISPLAY 0.702128 (-1925 -1150);
PAINT YELLOW (-1925 -1150);
FORCEPROP 1 LASTPIN (-1975 -1150) $PN 1
J 0
(-1965 -1170);
DISPLAY 0.808511 (-1965 -1170);
PAINT WHITE (-1965 -1170);
FORCEPROP 1 LASTPIN (-1975 -1350) $PN 2
J 0
(-1965 -1370);
DISPLAY 0.808511 (-1965 -1370);
PAINT WHITE (-1965 -1370);
FORCEPROP 0 LAST $SEC 1
J 0
(-1925 -1100);
DISPLAY 0.680851 (-1925 -1100);
PAINT MONO (-1925 -1100);
DISPLAY INVISIBLE (-1925 -1100);
FORCEPROP 0 LAST CDS_SEC 1
J 0
(-1925 -1100);
DISPLAY 1.021277 (-1925 -1100);
DISPLAY INVISIBLE (-1925 -1100);
FORCEADD UNIVERSAL_GND..1
(-1975 -1475);
FORCEPROP 3 LASTPIN (-1975 -1425) SIG_NAME GND\g
J 0
(-1965 -1415);
DISPLAY 0.659574 (-1965 -1415);
PAINT MONO (-1965 -1415);
DISPLAY INVISIBLE (-1965 -1415);
FORCEPROP 2 LAST CDS_LIB logical_power
J 0
(-1975 -1475);
DISPLAY INVISIBLE (-1975 -1475);
FORCEPROP 1 LAST HDL_POWER GND
J 1
(-1950 -1550);
DISPLAY 0.702128 (-1950 -1550);
PAINT GREEN (-1950 -1550);
DISPLAY INVISIBLE (-1950 -1550);
FORCEPROP 1 LAST PATH I64
J 0
(-1900 -1475);
DISPLAY 0.872340 (-1900 -1475);
PAINT AQUA (-1900 -1475);
DISPLAY INVISIBLE (-1900 -1475);
FORCEADD VCCAUX15..1
(-1700 -950);
FORCEPROP 3 LASTPIN (-1700 -1000) SIG_NAME P3V3_AUX\g
J 0
(-1690 -990);
DISPLAY 0.659574 (-1690 -990);
PAINT MONO (-1690 -990);
DISPLAY INVISIBLE (-1690 -990);
FORCEPROP 1 LAST HDL_POWER P3V3_AUX
J 1
(-1700 -900);
DISPLAY 0.702128 (-1700 -900);
PAINT GREEN (-1700 -900);
FORCEPROP 2 LAST CDS_LIB logical_power
J 0
(-1700 -950);
DISPLAY INVISIBLE (-1700 -950);
FORCEPROP 1 LAST PATH I65
J 0
(-1650 -925);
DISPLAY 0.872340 (-1650 -925);
PAINT AQUA (-1650 -925);
DISPLAY INVISIBLE (-1650 -925);
FORCEADD Q_CAP..1
(-775 -1300);
FORCEPROP 1 LAST TOLERANCE 10%
J 0
(-725 -1350);
DISPLAY 0.510638 (-725 -1350);
PAINT SKYBLUE (-725 -1350);
FORCEPROP 1 LAST PACK_TYPE 0402
J 0
(-725 -1500);
DISPLAY 0.510638 (-725 -1500);
PAINT SKYBLUE (-725 -1500);
FORCEPROP 1 LAST MATERIAL X7R
J 0
(-725 -1400);
DISPLAY 0.510638 (-725 -1400);
PAINT SKYBLUE (-725 -1400);
FORCEPROP 1 LAST PART_NUMBER CH4104K1B00
J 0
(-725 -1450);
DISPLAY 0.510638 (-725 -1450);
PAINT WHITE (-725 -1450);
FORCEPROP 1 LAST VALUE 0.1UF
J 0
(-725 -1250);
DISPLAY 0.510638 (-725 -1250);
PAINT SKYBLUE (-725 -1250);
FORCEPROP 1 LAST VOLTAGE 25V
J 0
(-725 -1300);
DISPLAY 0.510638 (-725 -1300);
PAINT SKYBLUE (-725 -1300);
FORCEPROP 1 LAST PATH I66
J 0
(-725 -1150);
DISPLAY 0.978723 (-725 -1150);
PAINT WHITE (-725 -1150);
DISPLAY INVISIBLE (-725 -1150);
FORCEPROP 2 LAST CDS_LIB pure_quanta
J 0
(-775 -1300);
DISPLAY INVISIBLE (-775 -1300);
FORCEPROP 1 LAST LOCATION C251
J 0
(-725 -1200);
DISPLAY 0.702128 (-725 -1200);
PAINT YELLOW (-725 -1200);
FORCEPROP 1 LASTPIN (-775 -1200) $PN 1
J 0
(-765 -1220);
DISPLAY 0.808511 (-765 -1220);
PAINT WHITE (-765 -1220);
FORCEPROP 1 LASTPIN (-775 -1400) $PN 2
J 0
(-765 -1420);
DISPLAY 0.808511 (-765 -1420);
PAINT WHITE (-765 -1420);
FORCEPROP 0 LAST $SEC 1
J 0
(-725 -1150);
DISPLAY 0.680851 (-725 -1150);
PAINT MONO (-725 -1150);
DISPLAY INVISIBLE (-725 -1150);
FORCEPROP 0 LAST CDS_SEC 1
J 0
(-725 -1150);
DISPLAY 1.021277 (-725 -1150);
DISPLAY INVISIBLE (-725 -1150);
FORCEADD UNIVERSAL_GND..1
(-775 -1525);
FORCEPROP 3 LASTPIN (-775 -1475) SIG_NAME GND\g
J 0
(-765 -1465);
DISPLAY 0.659574 (-765 -1465);
PAINT MONO (-765 -1465);
DISPLAY INVISIBLE (-765 -1465);
FORCEPROP 1 LAST PATH I67
J 0
(-700 -1525);
DISPLAY 0.872340 (-700 -1525);
PAINT AQUA (-700 -1525);
DISPLAY INVISIBLE (-700 -1525);
FORCEPROP 1 LAST HDL_POWER GND
J 1
(-750 -1600);
DISPLAY 0.702128 (-750 -1600);
PAINT GREEN (-750 -1600);
DISPLAY INVISIBLE (-750 -1600);
FORCEPROP 2 LAST CDS_LIB logical_power
J 0
(-775 -1525);
DISPLAY INVISIBLE (-775 -1525);
FORCEADD UNIVERSAL_POWER..1
(-900 -1025);
FORCEPROP 3 LASTPIN (-900 -1075) SIG_NAME P3V3_RGM\g
J 0
(-890 -1065);
DISPLAY 0.659574 (-890 -1065);
PAINT MONO (-890 -1065);
DISPLAY INVISIBLE (-890 -1065);
FORCEPROP 1 LAST HDL_POWER P3V3_RGM
J 1
(-900 -975);
DISPLAY 0.702128 (-900 -975);
PAINT GREEN (-900 -975);
FORCEPROP 1 LAST PATH I68
J 0
(-850 -1000);
DISPLAY 0.872340 (-850 -1000);
PAINT AQUA (-850 -1000);
DISPLAY INVISIBLE (-850 -1000);
FORCEPROP 2 LAST CDS_LIB logical_power
J 0
(-900 -1025);
DISPLAY INVISIBLE (-900 -1025);
FORCEADD Q_CAP..1
(-50 -2050);
FORCEPROP 1 LAST PACK_TYPE C0402
J 0
(0 -2250);
DISPLAY 0.510638 (0 -2250);
PAINT SKYBLUE (0 -2250);
FORCEPROP 1 LAST VOLTAGE 25V
J 0
(0 -2050);
DISPLAY 0.510638 (0 -2050);
PAINT SKYBLUE (0 -2050);
FORCEPROP 1 LAST VALUE 1UF
J 0
(0 -2000);
DISPLAY 0.510638 (0 -2000);
PAINT SKYBLUE (0 -2000);
FORCEPROP 1 LAST TOLERANCE 10%
J 0
(0 -2100);
DISPLAY 0.510638 (0 -2100);
PAINT SKYBLUE (0 -2100);
FORCEPROP 1 LAST MATERIAL EMPTY
J 0
(0 -2150);
DISPLAY 0.510638 (0 -2150);
PAINT RED (0 -2150);
FORCEPROP 1 LAST PART_NUMBER CH5104KEB02
J 0
(0 -2200);
DISPLAY 0.510638 (0 -2200);
PAINT WHITE (0 -2200);
FORCEPROP 2 LAST CDS_LIB pure_quanta
J 0
(-50 -2050);
DISPLAY INVISIBLE (-50 -2050);
FORCEPROP 2 LAST SEC_TYPE C0402
J 0
(0 -1850);
DISPLAY 0.680851 (0 -1850);
DISPLAY INVISIBLE (0 -1850);
FORCEPROP 1 LAST PATH I73
J 0
(0 -1900);
DISPLAY 0.978723 (0 -1900);
PAINT WHITE (0 -1900);
DISPLAY INVISIBLE (0 -1900);
FORCEPROP 1 LAST LOCATION C252
J 0
(0 -1950);
DISPLAY 0.702128 (0 -1950);
PAINT YELLOW (0 -1950);
FORCEPROP 1 LASTPIN (-50 -1950) $PN 1
J 0
(-40 -1970);
DISPLAY 0.808511 (-40 -1970);
PAINT WHITE (-40 -1970);
FORCEPROP 1 LASTPIN (-50 -2150) $PN 2
J 0
(-40 -2170);
DISPLAY 0.808511 (-40 -2170);
PAINT WHITE (-40 -2170);
FORCEPROP 2 LAST SEC 1
J 0
(0 -1850);
DISPLAY 0.680851 (0 -1850);
PAINT MONO (0 -1850);
DISPLAY INVISIBLE (0 -1850);
FORCEADD UNIVERSAL_GND..1
(-50 -2275);
FORCEPROP 3 LASTPIN (-50 -2225) SIG_NAME GND\g
J 0
(-40 -2215);
DISPLAY 0.659574 (-40 -2215);
PAINT MONO (-40 -2215);
DISPLAY INVISIBLE (-40 -2215);
FORCEPROP 2 LAST CDS_LIB logical_power
J 0
(-50 -2275);
DISPLAY INVISIBLE (-50 -2275);
FORCEPROP 1 LAST HDL_POWER GND
J 1
(-25 -2350);
DISPLAY 0.702128 (-25 -2350);
PAINT GREEN (-25 -2350);
DISPLAY INVISIBLE (-25 -2350);
FORCEPROP 1 LAST PATH I74
J 0
(25 -2275);
DISPLAY 0.872340 (25 -2275);
PAINT AQUA (25 -2275);
DISPLAY INVISIBLE (25 -2275);
FORCEADD OFFPAGE..5
R 2
(1375 -1700);
FORCEPROP 2 LAST $XR0 36 
J 0
(1564 -1700);
DISPLAY 0.638298 (1564 -1700);
PAINT MONO (1564 -1700);
FORCEPROP 2 LAST $XR1 54 
J 0
(1654 -1700);
DISPLAY 0.638298 (1654 -1700);
PAINT MONO (1654 -1700);
FORCEPROP 2 LAST $XR2 55 
J 0
(1744 -1700);
DISPLAY 0.638298 (1744 -1700);
PAINT MONO (1744 -1700);
FORCEPROP 1 LAST COMMENT_BODY TRUE
J 2
(1275 -1775);
DISPLAY 0.872340 (1275 -1775);
PAINT PEACH (1275 -1775);
DISPLAY INVISIBLE (1275 -1775);
FORCEPROP 1 LAST OFFPAGE TRUE
J 2
(1050 -1825);
DISPLAY 0.872340 (1050 -1825);
PAINT GREEN (1050 -1825);
DISPLAY INVISIBLE (1050 -1825);
FORCEPROP 2 LAST CDS_LIB standard
J 0
(1375 -1700);
DISPLAY INVISIBLE (1375 -1700);
FORCEPROP 2 LAST PATH I75
J 0
(1550 -1625);
DISPLAY 1.021277 (1550 -1625);
DISPLAY INVISIBLE (1550 -1625);
FORCEADD AP22811AW57..1
R 2
(-1275 -1750);
FORCEPROP 1 LAST MATERIAL IC
J 2
(-1106 -1618);
DISPLAY 0.510638 (-1106 -1618);
PAINT SKYBLUE (-1106 -1618);
FORCEPROP 0 LAST L DELAY: 1.7MS
J 2
(-825 -2400);
DISPLAY 1.021277 (-825 -2400);
PAINT WHITE (-825 -2400);
FORCEPROP 2 LAST PART_TYPE SMLF
J 2
(-1125 -1250);
DISPLAY 0.510638 (-1125 -1250);
PAINT SKYBLUE (-1125 -1250);
FORCEPROP 2 LAST VALUE AP22811AW5-7
J 2
(-1125 -1300);
DISPLAY 0.510638 (-1125 -1300);
PAINT SKYBLUE (-1125 -1300);
FORCEPROP 1 LAST PART_NUMBER AL022811000
J 2
(-1106 -1491);
DISPLAY 0.510638 (-1106 -1491);
PAINT WHITE (-1106 -1491);
FORCEPROP 1 LAST CDS_LMAN_SYM_OUTLINE -175,100,175,-100
J 2
(-1275 -1750);
DISPLAY 0.468085 (-1275 -1750);
PAINT GREEN (-1275 -1750);
DISPLAY INVISIBLE (-1275 -1750);
FORCEPROP 1 LAST NEEDS_NO_SIZE TRUE
J 2
(-1275 -1750);
DISPLAY 0.723404 (-1275 -1750);
PAINT GREEN (-1275 -1750);
DISPLAY INVISIBLE (-1275 -1750);
FORCEPROP 2 LAST CDS_LIB pure_quanta
J 2
(-1275 -1750);
DISPLAY INVISIBLE (-1275 -1750);
FORCEPROP 1 LAST PATH I79
J 2
(-1275 -1750);
DISPLAY 0.723404 (-1275 -1750);
PAINT GREEN (-1275 -1750);
DISPLAY INVISIBLE (-1275 -1750);
FORCEPROP 1 LAST LOCATION U14
J 2
(-1106 -1344);
DISPLAY 0.702128 (-1106 -1344);
PAINT AQUA (-1106 -1344);
FORCEPROP 0 LASTPIN (-1600 -1800) $PN 4
J 2
(-1610 -1790);
DISPLAY 0.680851 (-1610 -1790);
PAINT MONO (-1610 -1790);
FORCEPROP 0 LASTPIN (-950 -1800) $PN 3
J 0
(-940 -1790);
DISPLAY 0.680851 (-940 -1790);
PAINT MONO (-940 -1790);
FORCEPROP 0 LASTPIN (-950 -1750) $PN 2
J 0
(-940 -1740);
DISPLAY 0.680851 (-940 -1740);
PAINT MONO (-940 -1740);
FORCEPROP 0 LASTPIN (-1600 -1700) $PN 5
J 2
(-1610 -1690);
DISPLAY 0.680851 (-1610 -1690);
PAINT MONO (-1610 -1690);
FORCEPROP 0 LASTPIN (-950 -1700) $PN 1
J 0
(-940 -1690);
DISPLAY 0.680851 (-940 -1690);
PAINT MONO (-940 -1690);
FORCEPROP 0 LAST $SEC 1
J 0
(-1125 -1225);
DISPLAY 0.680851 (-1125 -1225);
PAINT MONO (-1125 -1225);
DISPLAY INVISIBLE (-1125 -1225);
FORCEPROP 0 LAST CDS_SEC 1
J 0
(-1125 -1225);
DISPLAY 1.021277 (-1125 -1225);
DISPLAY INVISIBLE (-1125 -1225);
FORCEADD Q_CAP..1
(-2125 2050);
FORCEPROP 1 LAST VALUE 22UF
J 0
(-2075 2100);
DISPLAY 0.510638 (-2075 2100);
PAINT SKYBLUE (-2075 2100);
FORCEPROP 1 LAST VOLTAGE 16V
J 0
(-2075 2050);
DISPLAY 0.510638 (-2075 2050);
PAINT SKYBLUE (-2075 2050);
FORCEPROP 1 LAST TOLERANCE 20%
J 0
(-2075 2000);
DISPLAY 0.510638 (-2075 2000);
PAINT SKYBLUE (-2075 2000);
FORCEPROP 1 LAST MATERIAL X6S
J 0
(-2075 1950);
DISPLAY 0.510638 (-2075 1950);
PAINT SKYBLUE (-2075 1950);
FORCEPROP 1 LAST PART_NUMBER CH6223MEA01
J 0
(-2075 1900);
DISPLAY 0.510638 (-2075 1900);
PAINT WHITE (-2075 1900);
FORCEPROP 1 LAST PACK_TYPE C0805
J 0
(-2075 1850);
DISPLAY 0.510638 (-2075 1850);
PAINT SKYBLUE (-2075 1850);
FORCEPROP 2 LAST CDS_LIB pure_quanta
J 0
(-2125 2050);
DISPLAY INVISIBLE (-2125 2050);
FORCEPROP 2 LAST SEC_TYPE C0805
J 0
(-2075 2250);
DISPLAY 0.680851 (-2075 2250);
DISPLAY INVISIBLE (-2075 2250);
FORCEPROP 1 LAST PATH I80
J 0
(-2075 2200);
DISPLAY 0.978723 (-2075 2200);
PAINT WHITE (-2075 2200);
DISPLAY INVISIBLE (-2075 2200);
FORCEPROP 1 LAST LOCATION PC219
J 0
(-2075 2150);
DISPLAY 0.702128 (-2075 2150);
PAINT AQUA (-2075 2150);
FORCEPROP 1 LASTPIN (-2125 2150) $PN 1
J 0
(-2115 2130);
DISPLAY 0.808511 (-2115 2130);
PAINT WHITE (-2115 2130);
FORCEPROP 1 LASTPIN (-2125 1950) $PN 2
J 0
(-2115 1930);
DISPLAY 0.808511 (-2115 1930);
PAINT WHITE (-2115 1930);
FORCEPROP 2 LAST SEC 1
J 0
(-2075 2250);
DISPLAY 0.680851 (-2075 2250);
PAINT MONO (-2075 2250);
DISPLAY INVISIBLE (-2075 2250);
FORCEADD Q_CAP..1
(-1725 2050);
FORCEPROP 1 LAST VALUE 22UF
J 0
(-1675 2100);
DISPLAY 0.510638 (-1675 2100);
PAINT SKYBLUE (-1675 2100);
FORCEPROP 1 LAST TOLERANCE 20%
J 0
(-1675 2000);
DISPLAY 0.510638 (-1675 2000);
PAINT SKYBLUE (-1675 2000);
FORCEPROP 1 LAST VOLTAGE 16V
J 0
(-1675 2050);
DISPLAY 0.510638 (-1675 2050);
PAINT SKYBLUE (-1675 2050);
FORCEPROP 1 LAST MATERIAL X6S
J 0
(-1675 1950);
DISPLAY 0.510638 (-1675 1950);
PAINT SKYBLUE (-1675 1950);
FORCEPROP 1 LAST PACK_TYPE C0805
J 0
(-1675 1850);
DISPLAY 0.510638 (-1675 1850);
PAINT SKYBLUE (-1675 1850);
FORCEPROP 1 LAST PART_NUMBER CH6223MEA01
J 0
(-1675 1900);
DISPLAY 0.510638 (-1675 1900);
PAINT WHITE (-1675 1900);
FORCEPROP 1 LAST PATH I81
J 0
(-1675 2200);
DISPLAY 0.978723 (-1675 2200);
PAINT WHITE (-1675 2200);
DISPLAY INVISIBLE (-1675 2200);
FORCEPROP 2 LAST CDS_LIB pure_quanta
J 0
(-1725 2050);
DISPLAY INVISIBLE (-1725 2050);
FORCEPROP 2 LAST SEC_TYPE C0805
J 0
(-1675 2250);
DISPLAY 0.680851 (-1675 2250);
DISPLAY INVISIBLE (-1675 2250);
FORCEPROP 1 LAST LOCATION PC218
J 0
(-1675 2150);
DISPLAY 0.702128 (-1675 2150);
PAINT AQUA (-1675 2150);
FORCEPROP 1 LASTPIN (-1725 2150) $PN 1
J 0
(-1715 2130);
DISPLAY 0.808511 (-1715 2130);
PAINT WHITE (-1715 2130);
FORCEPROP 1 LASTPIN (-1725 1950) $PN 2
J 0
(-1715 1930);
DISPLAY 0.808511 (-1715 1930);
PAINT WHITE (-1715 1930);
FORCEPROP 2 LAST SEC 1
J 0
(-1675 2250);
DISPLAY 0.680851 (-1675 2250);
PAINT MONO (-1675 2250);
DISPLAY INVISIBLE (-1675 2250);
FORCEADD MPQ8626GDZ..1
(-275 1150);
FORCEPROP 2 LAST PART_TYPE SMLF
J 0
(-475 2275);
DISPLAY 0.510638 (-475 2275);
PAINT SKYBLUE (-475 2275);
FORCEPROP 2 LAST VALUE MPQ8626GD-Z
J 0
(-475 2225);
DISPLAY 0.510638 (-475 2225);
PAINT SKYBLUE (-475 2225);
FORCEPROP 1 LAST MATERIAL IC
J 0
(-495 1907);
DISPLAY 0.510638 (-495 1907);
PAINT SKYBLUE (-495 1907);
FORCEPROP 1 LAST PART_NUMBER AL008626000
J 0
(-495 2034);
DISPLAY 0.510638 (-495 2034);
PAINT WHITE (-495 2034);
FORCEPROP 1 LAST CDS_LMAN_SYM_OUTLINE -250,725,250,-725
J 0
(-275 1150);
DISPLAY 0.468085 (-275 1150);
PAINT GREEN (-275 1150);
DISPLAY INVISIBLE (-275 1150);
FORCEPROP 1 LAST NEEDS_NO_SIZE TRUE
J 0
(-275 1150);
DISPLAY 0.723404 (-275 1150);
PAINT GREEN (-275 1150);
DISPLAY INVISIBLE (-275 1150);
FORCEPROP 2 LAST CDS_LIB pure_quanta
J 0
(-275 1150);
DISPLAY INVISIBLE (-275 1150);
FORCEPROP 1 LAST PATH I82
J 0
(-275 1150);
DISPLAY 0.723404 (-275 1150);
PAINT GREEN (-275 1150);
DISPLAY INVISIBLE (-275 1150);
FORCEPROP 1 LAST LOCATION PU1
J 0
(-495 2181);
DISPLAY 0.702128 (-495 2181);
PAINT AQUA (-495 2181);
FORCEPROP 0 LASTPIN (125 475) $PN 7
J 0
(135 485);
DISPLAY 0.680851 (135 485);
PAINT MONO (135 485);
FORCEPROP 0 LASTPIN (125 1625) $PN 10
J 0
(135 1635);
DISPLAY 0.680851 (135 1635);
PAINT MONO (135 1635);
FORCEPROP 0 LASTPIN (-675 525) $PN 4
J 2
(-685 535);
DISPLAY 0.680851 (-685 535);
PAINT MONO (-685 535);
FORCEPROP 0 LASTPIN (-675 1325) $PN 5
J 2
(-685 1335);
DISPLAY 0.680851 (-685 1335);
PAINT MONO (-685 1335);
FORCEPROP 0 LASTPIN (125 875) $PN 6
J 0
(135 885);
DISPLAY 0.680851 (135 885);
PAINT MONO (135 885);
FORCEPROP 0 LASTPIN (-675 1125) $PN 12
J 2
(-685 1135);
DISPLAY 0.680851 (-685 1135);
PAINT MONO (-685 1135);
FORCEPROP 0 LASTPIN (125 725) $PN 1
J 0
(135 735);
DISPLAY 0.680851 (135 735);
PAINT MONO (135 735);
FORCEPROP 0 LASTPIN (125 525) $PN 14
J 0
(135 535);
DISPLAY 0.680851 (135 535);
PAINT MONO (135 535);
FORCEPROP 0 LASTPIN (125 1825) $PN 9
J 0
(135 1835);
DISPLAY 0.680851 (135 1835);
PAINT MONO (135 1835);
FORCEPROP 0 LASTPIN (125 1375) $PN 2
J 0
(135 1385);
DISPLAY 0.680851 (135 1385);
PAINT MONO (135 1385);
FORCEPROP 0 LASTPIN (125 1325) $PN 11
J 0
(135 1335);
DISPLAY 0.680851 (135 1335);
PAINT MONO (135 1335);
FORCEPROP 0 LASTPIN (125 625) $PN 8
J 0
(135 635);
DISPLAY 0.680851 (135 635);
PAINT MONO (135 635);
FORCEPROP 0 LASTPIN (-675 875) $PN 13
J 2
(-685 885);
DISPLAY 0.680851 (-685 885);
PAINT MONO (-685 885);
FORCEPROP 0 LASTPIN (-675 1825) $PN 3
J 2
(-685 1835);
DISPLAY 0.680851 (-685 1835);
PAINT MONO (-685 1835);
FORCEPROP 0 LAST $SEC 1
J 0
(-475 2300);
DISPLAY 0.680851 (-475 2300);
PAINT MONO (-475 2300);
DISPLAY INVISIBLE (-475 2300);
FORCEPROP 0 LAST CDS_SEC 1
J 0
(-475 2300);
DISPLAY 1.021277 (-475 2300);
DISPLAY INVISIBLE (-475 2300);
FORCEADD UNIVERSAL_GND..1
(-1200 -150);
FORCEPROP 3 LASTPIN (-1200 -100) SIG_NAME GND\g
J 0
(-1190 -90);
DISPLAY 0.659574 (-1190 -90);
PAINT MONO (-1190 -90);
DISPLAY INVISIBLE (-1190 -90);
FORCEPROP 2 LAST CDS_LIB logical_power
J 0
(-1200 -150);
DISPLAY INVISIBLE (-1200 -150);
FORCEPROP 1 LAST HDL_POWER GND
J 1
(-1175 -225);
DISPLAY 0.702128 (-1175 -225);
PAINT GREEN (-1175 -225);
DISPLAY INVISIBLE (-1175 -225);
FORCEPROP 1 LAST PATH I84
J 0
(-1125 -150);
DISPLAY 0.872340 (-1125 -150);
PAINT AQUA (-1125 -150);
DISPLAY INVISIBLE (-1125 -150);
FORCEADD UNIVERSAL_GND..1
(800 -150);
FORCEPROP 3 LASTPIN (800 -100) SIG_NAME GND\g
J 0
(810 -90);
DISPLAY 0.659574 (810 -90);
PAINT MONO (810 -90);
DISPLAY INVISIBLE (810 -90);
FORCEPROP 2 LAST CDS_LIB logical_power
J 0
(800 -150);
DISPLAY INVISIBLE (800 -150);
FORCEPROP 1 LAST HDL_POWER GND
J 1
(825 -225);
DISPLAY 0.702128 (825 -225);
PAINT GREEN (825 -225);
DISPLAY INVISIBLE (825 -225);
FORCEPROP 1 LAST PATH I85
J 0
(875 -150);
DISPLAY 0.872340 (875 -150);
PAINT AQUA (875 -150);
DISPLAY INVISIBLE (875 -150);
FORCEADD Q_CAP..1
(800 150);
FORCEPROP 1 LAST VALUE 3300PF
J 0
(850 200);
DISPLAY 0.510638 (850 200);
PAINT SKYBLUE (850 200);
FORCEPROP 1 LAST VOLTAGE 50V
J 0
(850 150);
DISPLAY 0.510638 (850 150);
PAINT SKYBLUE (850 150);
FORCEPROP 1 LAST MATERIAL X7R
J 0
(850 50);
DISPLAY 0.510638 (850 50);
PAINT SKYBLUE (850 50);
FORCEPROP 1 LAST TOLERANCE 10%
J 0
(850 100);
DISPLAY 0.510638 (850 100);
PAINT SKYBLUE (850 100);
FORCEPROP 1 LAST PART_NUMBER TMP_QCH2336K1B12
J 0
(850 0);
DISPLAY 0.510638 (850 0);
PAINT WHITE (850 0);
FORCEPROP 1 LAST PACK_TYPE 0402
J 0
(850 -50);
DISPLAY 0.510638 (850 -50);
PAINT SKYBLUE (850 -50);
FORCEPROP 2 LAST CDS_LIB pure_quanta
J 0
(800 150);
DISPLAY INVISIBLE (800 150);
FORCEPROP 1 LAST PATH I86
J 0
(850 300);
DISPLAY 0.978723 (850 300);
PAINT WHITE (850 300);
DISPLAY INVISIBLE (850 300);
FORCEPROP 1 LAST LOCATION PC273
J 0
(850 250);
DISPLAY 0.702128 (850 250);
PAINT AQUA (850 250);
FORCEPROP 0 LAST $SEC 1
J 0
(850 300);
DISPLAY 0.680851 (850 300);
PAINT MONO (850 300);
DISPLAY INVISIBLE (850 300);
FORCEPROP 0 LAST CDS_SEC 1
J 0
(850 300);
DISPLAY 1.021277 (850 300);
DISPLAY INVISIBLE (850 300);
FORCEPROP 1 LASTPIN (800 250) $PN 1
J 0
(810 230);
DISPLAY 0.808511 (810 230);
PAINT WHITE (810 230);
DISPLAY INVISIBLE (810 230);
FORCEPROP 1 LASTPIN (800 50) $PN 2
J 0
(810 30);
DISPLAY 0.808511 (810 30);
PAINT WHITE (810 30);
DISPLAY INVISIBLE (810 30);
FORCEADD Q_RES..2
R 6
(-1200 150);
FORCEPROP 1 LAST TOLERANCE 1%
J 0
(-1155 125);
DISPLAY 0.510638 (-1155 125);
PAINT SKYBLUE (-1155 125);
FORCEPROP 1 LAST PACK_TYPE 0402LF
J 0
(-1160 325);
DISPLAY 0.510638 (-1160 325);
PAINT SKYBLUE (-1160 325);
FORCEPROP 1 LAST WATTAGE 1/16W
J 0
(-1160 175);
DISPLAY 0.510638 (-1160 175);
PAINT SKYBLUE (-1160 175);
FORCEPROP 1 LAST VALUE 5.49K
J 0
(-1155 75);
DISPLAY 0.510638 (-1155 75);
PAINT SKYBLUE (-1155 75);
FORCEPROP 1 LAST PART_NUMBER CS25492FB02
J 0
(-1160 275);
DISPLAY 0.510638 (-1160 275);
PAINT WHITE (-1160 275);
FORCEPROP 1 LAST MATERIAL CHIP
J 0
(-1160 225);
DISPLAY 0.510638 (-1160 225);
PAINT SKYBLUE (-1160 225);
FORCEPROP 2 LAST SEC_TYPE 0402LF
J 0
(-1150 350);
DISPLAY 0.680851 (-1150 350);
DISPLAY INVISIBLE (-1150 350);
FORCEPROP 2 LAST CDS_LIB pure_quanta
J 0
(-1200 150);
DISPLAY INVISIBLE (-1200 150);
FORCEPROP 1 LAST PATH I87
J 0
(-1150 -25);
DISPLAY 0.978723 (-1150 -25);
PAINT WHITE (-1150 -25);
DISPLAY INVISIBLE (-1150 -25);
FORCEPROP 1 LAST LOCATION PR276
J 0
(-1155 25);
DISPLAY 0.702128 (-1155 25);
PAINT AQUA (-1155 25);
FORCEPROP 1 LASTPIN (-1200 50) $PN 1
J 0
(-1195 88);
DISPLAY 0.808511 (-1195 88);
PAINT WHITE (-1195 88);
FORCEPROP 1 LASTPIN (-1200 250) $PN 2
J 0
(-1195 240);
DISPLAY 0.808511 (-1195 240);
PAINT WHITE (-1195 240);
FORCEPROP 2 LAST SEC 1
J 0
(-1150 350);
DISPLAY 0.680851 (-1150 350);
PAINT MONO (-1150 350);
DISPLAY INVISIBLE (-1150 350);
FORCEADD Q_RES..2
R 6
(-2025 750);
FORCEPROP 1 LAST PACK_TYPE 0402LF
J 0
(-1985 925);
DISPLAY 0.510638 (-1985 925);
PAINT SKYBLUE (-1985 925);
FORCEPROP 1 LAST MATERIAL CHIP
J 0
(-1985 825);
DISPLAY 0.510638 (-1985 825);
PAINT SKYBLUE (-1985 825);
FORCEPROP 1 LAST VALUE 60.4K
J 0
(-1980 675);
DISPLAY 0.510638 (-1980 675);
PAINT SKYBLUE (-1980 675);
FORCEPROP 1 LAST TOLERANCE 1%
J 0
(-1980 725);
DISPLAY 0.510638 (-1980 725);
PAINT SKYBLUE (-1980 725);
FORCEPROP 1 LAST WATTAGE 1/16W
J 0
(-1985 775);
DISPLAY 0.510638 (-1985 775);
PAINT SKYBLUE (-1985 775);
FORCEPROP 1 LAST PART_NUMBER CS36042FB04
J 0
(-1985 875);
DISPLAY 0.510638 (-1985 875);
PAINT WHITE (-1985 875);
FORCEPROP 2 LAST CDS_LIB pure_quanta
J 0
(-2025 750);
DISPLAY INVISIBLE (-2025 750);
FORCEPROP 1 LAST PATH I88
J 0
(-1975 575);
DISPLAY 0.978723 (-1975 575);
PAINT WHITE (-1975 575);
DISPLAY INVISIBLE (-1975 575);
FORCEPROP 1 LAST LOCATION PR532
J 0
(-1980 625);
DISPLAY 0.702128 (-1980 625);
PAINT AQUA (-1980 625);
FORCEPROP 0 LAST $SEC 1
J 0
(-1975 950);
DISPLAY 0.680851 (-1975 950);
PAINT MONO (-1975 950);
DISPLAY INVISIBLE (-1975 950);
FORCEPROP 0 LAST CDS_SEC 1
J 0
(-1975 950);
DISPLAY 1.021277 (-1975 950);
DISPLAY INVISIBLE (-1975 950);
FORCEPROP 1 LASTPIN (-2025 650) $PN 1
J 0
(-2020 688);
DISPLAY 0.808511 (-2020 688);
PAINT WHITE (-2020 688);
DISPLAY INVISIBLE (-2020 688);
FORCEPROP 1 LASTPIN (-2025 850) $PN 2
J 0
(-2020 840);
DISPLAY 0.808511 (-2020 840);
PAINT WHITE (-2020 840);
DISPLAY INVISIBLE (-2020 840);
FORCEADD UNIVERSAL_GND..1
(-2025 450);
FORCEPROP 3 LASTPIN (-2025 500) SIG_NAME GND\g
J 0
(-2015 510);
DISPLAY 0.659574 (-2015 510);
PAINT MONO (-2015 510);
DISPLAY INVISIBLE (-2015 510);
FORCEPROP 2 LAST CDS_LIB logical_power
J 0
(-2025 450);
DISPLAY INVISIBLE (-2025 450);
FORCEPROP 1 LAST HDL_POWER GND
J 1
(-2000 375);
DISPLAY 0.702128 (-2000 375);
PAINT GREEN (-2000 375);
DISPLAY INVISIBLE (-2000 375);
FORCEPROP 1 LAST PATH I89
J 0
(-1950 450);
DISPLAY 0.872340 (-1950 450);
PAINT AQUA (-1950 450);
DISPLAY INVISIBLE (-1950 450);
FORCEADD Q_CAP..1
(-1600 500);
FORCEPROP 1 LAST PACK_TYPE C0402
J 0
(-1550 300);
DISPLAY 0.510638 (-1550 300);
PAINT SKYBLUE (-1550 300);
FORCEPROP 1 LAST VALUE 1UF
J 0
(-1550 550);
DISPLAY 0.510638 (-1550 550);
PAINT SKYBLUE (-1550 550);
FORCEPROP 1 LAST VOLTAGE 25V
J 0
(-1550 500);
DISPLAY 0.510638 (-1550 500);
PAINT SKYBLUE (-1550 500);
FORCEPROP 1 LAST PART_NUMBER CH5104KEB02
J 0
(-1550 350);
DISPLAY 0.510638 (-1550 350);
PAINT WHITE (-1550 350);
FORCEPROP 1 LAST MATERIAL X6S
J 0
(-1550 400);
DISPLAY 0.510638 (-1550 400);
PAINT SKYBLUE (-1550 400);
FORCEPROP 1 LAST TOLERANCE 10%
J 0
(-1550 450);
DISPLAY 0.510638 (-1550 450);
PAINT SKYBLUE (-1550 450);
FORCEPROP 2 LAST SEC_TYPE C0402
J 0
(-1550 700);
DISPLAY 1.021277 (-1550 700);
DISPLAY INVISIBLE (-1550 700);
FORCEPROP 2 LAST CDS_LIB pure_quanta
J 0
(-1600 500);
DISPLAY INVISIBLE (-1600 500);
FORCEPROP 1 LAST PATH I9
J 0
(-1550 650);
DISPLAY 0.978723 (-1550 650);
PAINT WHITE (-1550 650);
DISPLAY INVISIBLE (-1550 650);
FORCEPROP 1 LAST LOCATION PC221
J 0
(-1550 600);
DISPLAY 0.702128 (-1550 600);
PAINT AQUA (-1550 600);
FORCEPROP 1 LASTPIN (-1600 600) $PN 1
J 0
(-1590 580);
DISPLAY 0.808511 (-1590 580);
PAINT WHITE (-1590 580);
FORCEPROP 1 LASTPIN (-1600 400) $PN 2
J 0
(-1590 380);
DISPLAY 0.808511 (-1590 380);
PAINT WHITE (-1590 380);
FORCEPROP 2 LAST SEC 1
J 0
(-1550 700);
DISPLAY 0.680851 (-1550 700);
PAINT MONO (-1550 700);
DISPLAY INVISIBLE (-1550 700);
FORCEADD Q_CAP..2
(3200 125);
FORCEPROP 1 LAST PACK_TYPE 0402
J 1
(3200 -75);
DISPLAY 0.510638 (3200 -75);
PAINT SKYBLUE (3200 -75);
FORCEPROP 1 LAST TOLERANCE 5%
J 2
(3200 -25);
DISPLAY 0.510638 (3200 -25);
PAINT SKYBLUE (3200 -25);
FORCEPROP 1 LAST MATERIAL NPO
J 0
(3200 -25);
DISPLAY 0.510638 (3200 -25);
PAINT SKYBLUE (3200 -25);
FORCEPROP 1 LAST VALUE 100PF
J 2
(3200 25);
DISPLAY 0.510638 (3200 25);
PAINT SKYBLUE (3200 25);
FORCEPROP 1 LAST VOLTAGE 50V
J 0
(3200 25);
DISPLAY 0.510638 (3200 25);
PAINT SKYBLUE (3200 25);
FORCEPROP 1 LAST PART_NUMBER CH11006JB00
J 1
(3675 0);
DISPLAY 0.510638 (3675 0);
PAINT WHITE (3675 0);
FORCEPROP 2 LAST CDS_LIB pure_quanta
J 0
(3200 125);
DISPLAY INVISIBLE (3200 125);
FORCEPROP 1 LAST PATH I91
J 0
(3200 325);
DISPLAY 0.978723 (3200 325);
PAINT WHITE (3200 325);
DISPLAY INVISIBLE (3200 325);
FORCEPROP 1 LAST LOCATION PC239
J 1
(3025 150);
DISPLAY 0.702128 (3025 150);
PAINT AQUA (3025 150);
FORCEPROP 0 LAST $SEC 1
J 0
(3025 200);
DISPLAY 0.680851 (3025 200);
PAINT MONO (3025 200);
DISPLAY INVISIBLE (3025 200);
FORCEPROP 0 LAST CDS_SEC 1
J 0
(3025 200);
DISPLAY 1.021277 (3025 200);
DISPLAY INVISIBLE (3025 200);
FORCEPROP 1 LASTPIN (3100 125) $PN 1
J 0
(3090 140);
DISPLAY 0.808511 (3090 140);
PAINT WHITE (3090 140);
DISPLAY INVISIBLE (3090 140);
FORCEPROP 1 LASTPIN (3300 125) $PN 2
J 0
(3285 140);
DISPLAY 0.808511 (3285 140);
PAINT WHITE (3285 140);
DISPLAY INVISIBLE (3285 140);
FORCEADD Q_INDUCTOR..1
(1850 1350);
FORCEPROP 1 LAST MATERIAL IND
J 0
(1725 1405);
DISPLAY 0.510638 (1725 1405);
PAINT SKYBLUE (1725 1405);
FORCEPROP 2 LAST PACK_TYPE SMLF
J 0
(1725 1550);
DISPLAY 0.510638 (1725 1550);
PAINT SKYBLUE (1725 1550);
FORCEPROP 2 LAST VALUE 3.3UH/6A
J 0
(1725 1600);
DISPLAY 0.510638 (1725 1600);
PAINT SKYBLUE (1725 1600);
FORCEPROP 1 LAST PART_NUMBER CV-3360MZ07
J 0
(1725 1460);
DISPLAY 0.510638 (1725 1460);
PAINT WHITE (1725 1460);
FORCEPROP 2 LAST CDS_LIB pure_quanta
J 0
(1850 1350);
DISPLAY INVISIBLE (1850 1350);
FORCEPROP 1 LAST NEEDS_NO_SIZE TRUE
J 0
(1850 1350);
DISPLAY 0.468085 (1850 1350);
PAINT GREEN (1850 1350);
DISPLAY INVISIBLE (1850 1350);
FORCEPROP 1 LAST PATH I92
J 0
(1925 1405);
DISPLAY 0.723404 (1925 1405);
PAINT GREEN (1925 1405);
DISPLAY INVISIBLE (1925 1405);
FORCEPROP 1 LAST LOCATION PL35
J 0
(1725 1510);
DISPLAY 0.702128 (1725 1510);
PAINT AQUA (1725 1510);
FORCEPROP 0 LASTPIN (1750 1325) $PN 1
J 2
(1740 1335);
DISPLAY 0.680851 (1740 1335);
PAINT MONO (1740 1335);
FORCEPROP 0 LASTPIN (1950 1325) $PN 2
J 0
(1960 1335);
DISPLAY 0.680851 (1960 1335);
PAINT MONO (1960 1335);
FORCEPROP 0 LAST $SEC 1
J 0
(1725 1625);
DISPLAY 0.680851 (1725 1625);
PAINT MONO (1725 1625);
DISPLAY INVISIBLE (1725 1625);
FORCEPROP 0 LAST CDS_SEC 1
J 0
(1725 1625);
DISPLAY 1.021277 (1725 1625);
DISPLAY INVISIBLE (1725 1625);
FORCEADD Q_CAP..1
(2175 1625);
FORCEPROP 1 LAST PACK_TYPE C0402
J 0
(2225 1425);
DISPLAY 0.787234 (2225 1425);
FORCEPROP 1 LAST MATERIAL EMPTY
J 0
(2225 1525);
DISPLAY 0.787234 (2225 1525);
FORCEPROP 1 LAST PART_NUMBER CH30106KB19
J 0
(2225 1475);
DISPLAY 0.787234 (2225 1475);
FORCEPROP 1 LAST TOLERANCE 10%
J 0
(2225 1575);
DISPLAY 0.787234 (2225 1575);
FORCEPROP 1 LAST VOLTAGE 50V
J 0
(2225 1625);
DISPLAY 0.787234 (2225 1625);
FORCEPROP 1 LAST VALUE 0.001UF
J 0
(2225 1675);
DISPLAY 0.787234 (2225 1675);
FORCEPROP 1 LAST PATH I93
J 0
(2225 1775);
DISPLAY 0.978723 (2225 1775);
PAINT WHITE (2225 1775);
DISPLAY INVISIBLE (2225 1775);
FORCEPROP 2 LAST CDS_LIB pure_quanta
J 0
(2175 1625);
DISPLAY INVISIBLE (2175 1625);
FORCEPROP 1 LAST LOCATION C151
J 0
(2225 1725);
DISPLAY 0.787234 (2225 1725);
FORCEPROP 1 LASTPIN (2175 1725) $PN 1
J 0
(2185 1705);
DISPLAY 0.787234 (2185 1705);
PAINT MONO (2185 1705);
FORCEPROP 1 LASTPIN (2175 1525) $PN 2
J 0
(2185 1505);
DISPLAY 0.787234 (2185 1505);
PAINT MONO (2185 1505);
FORCEPROP 0 LAST $SEC 1
J 0
(2225 1775);
DISPLAY 0.680851 (2225 1775);
PAINT MONO (2225 1775);
DISPLAY INVISIBLE (2225 1775);
FORCEPROP 0 LAST CDS_SEC 1
J 0
(2225 1775);
DISPLAY 0.680851 (2225 1775);
DISPLAY INVISIBLE (2225 1775);
FORCEADD UNIVERSAL_GND..1
(2175 1425);
FORCEPROP 3 LASTPIN (2175 1475) SIG_NAME GND\g
J 0
(2185 1485);
DISPLAY 0.659574 (2185 1485);
PAINT MONO (2185 1485);
DISPLAY INVISIBLE (2185 1485);
FORCEPROP 2 LAST CDS_LIB logical_power
J 0
(2175 1425);
DISPLAY INVISIBLE (2175 1425);
FORCEPROP 1 LAST PATH I94
J 0
(2250 1425);
DISPLAY 0.872340 (2250 1425);
PAINT AQUA (2250 1425);
DISPLAY INVISIBLE (2250 1425);
FORCEPROP 1 LAST HDL_POWER GND
J 1
(2200 1350);
DISPLAY 0.702128 (2200 1350);
PAINT GREEN (2200 1350);
DISPLAY INVISIBLE (2200 1350);
FORCEADD Q_RES..1
(2975 1825);
FORCEPROP 1 LAST VALUE 0
J 2
(2950 1725);
DISPLAY 0.978723 (2950 1725);
FORCEPROP 1 LAST MATERIAL CHIP
J 0
(2975 1675);
DISPLAY 0.978723 (2975 1675);
FORCEPROP 1 LAST TOLERANCE 5%
J 0
(2975 1725);
DISPLAY 0.978723 (2975 1725);
FORCEPROP 1 LAST PACK_TYPE 0402LF
J 0
(3225 1675);
DISPLAY 0.978723 (3225 1675);
FORCEPROP 1 LAST PART_NUMBER CS00002JB13
J 0
(2925 1925);
DISPLAY 0.978723 (2925 1925);
FORCEPROP 1 LAST WATTAGE 1/16W
J 2
(2950 1675);
DISPLAY 0.978723 (2950 1675);
FORCEPROP 2 LAST CDS_LIB pure_quanta
J 0
(2975 1825);
DISPLAY INVISIBLE (2975 1825);
FORCEPROP 1 LAST PATH I95
J 0
(2925 1975);
DISPLAY 0.978723 (2925 1975);
PAINT WHITE (2925 1975);
DISPLAY INVISIBLE (2925 1975);
FORCEPROP 1 LAST LOCATION R293
J 0
(2925 1875);
DISPLAY 0.978723 (2925 1875);
FORCEPROP 1 LASTPIN (2875 1825) $PN 1
J 0
(2887 1837);
DISPLAY 0.787234 (2887 1837);
PAINT MONO (2887 1837);
FORCEPROP 1 LASTPIN (3075 1825) $PN 2
J 0
(3037 1837);
DISPLAY 0.787234 (3037 1837);
PAINT MONO (3037 1837);
FORCEPROP 0 LAST $SEC 1
J 0
(2925 1975);
DISPLAY 0.680851 (2925 1975);
PAINT MONO (2925 1975);
DISPLAY INVISIBLE (2925 1975);
FORCEPROP 0 LAST CDS_SEC 1
J 0
(2925 1975);
DISPLAY 0.680851 (2925 1975);
DISPLAY INVISIBLE (2925 1975);
FORCEADD Q_RES..1
(400 -1700);
FORCEPROP 1 LAST MATERIAL CHIP
J 0
(550 -1700);
DISPLAY 0.510638 (550 -1700);
PAINT SKYBLUE (550 -1700);
FORCEPROP 1 LAST VALUE 0
J 2
(525 -1700);
DISPLAY 0.510638 (525 -1700);
PAINT SKYBLUE (525 -1700);
FORCEPROP 1 LAST PACK_TYPE 0402LF
J 0
(325 -1750);
DISPLAY 0.510638 (325 -1750);
PAINT SKYBLUE (325 -1750);
FORCEPROP 1 LAST PART_NUMBER CS00002JB13
J 0
(300 -1650);
DISPLAY 0.510638 (300 -1650);
PAINT WHITE (300 -1650);
FORCEPROP 2 LAST CDS_LIB pure_quanta
J 0
(400 -1700);
DISPLAY INVISIBLE (400 -1700);
FORCEPROP 1 LAST PATH I96
J 0
(350 -1550);
DISPLAY 0.978723 (350 -1550);
PAINT WHITE (350 -1550);
DISPLAY INVISIBLE (350 -1550);
FORCEPROP 1 LAST WATTAGE 1/16W
J 2
(375 -1850);
DISPLAY 0.510638 (375 -1850);
PAINT SKYBLUE (375 -1850);
DISPLAY INVISIBLE (375 -1850);
FORCEPROP 1 LAST TOLERANCE 5%
J 0
(400 -1800);
DISPLAY 0.510638 (400 -1800);
PAINT SKYBLUE (400 -1800);
DISPLAY INVISIBLE (400 -1800);
FORCEPROP 1 LAST LOCATION R99
J 0
(225 -1700);
DISPLAY 0.702128 (225 -1700);
PAINT YELLOW (225 -1700);
FORCEPROP 1 LASTPIN (300 -1700) $PN 1
J 0
(312 -1688);
DISPLAY 0.808511 (312 -1688);
PAINT WHITE (312 -1688);
FORCEPROP 1 LASTPIN (500 -1700) $PN 2
J 0
(462 -1688);
DISPLAY 0.808511 (462 -1688);
PAINT WHITE (462 -1688);
FORCEPROP 2 LAST $SEC 1
J 0
(275 -1475);
DISPLAY 0.680851 (275 -1475);
PAINT MONO (275 -1475);
DISPLAY INVISIBLE (275 -1475);
FORCEPROP 0 LAST CDS_SEC 1
J 0
(275 -1475);
DISPLAY 0.680851 (275 -1475);
PAINT MONO (275 -1475);
DISPLAY INVISIBLE (275 -1475);
FORCEADD Q_RES..1
(-1625 1325);
FORCEPROP 1 LAST TOLERANCE 5%
J 0
(-2025 1250);
DISPLAY 0.978723 (-2025 1250);
FORCEPROP 1 LAST WATTAGE 1/16W
J 2
(-1700 1250);
DISPLAY 0.978723 (-1700 1250);
FORCEPROP 1 LAST PART_NUMBER CS00002JB13
J 0
(-1850 1425);
DISPLAY 0.978723 (-1850 1425);
FORCEPROP 1 LAST PACK_TYPE 0402LF
J 0
(-1675 1250);
DISPLAY 0.978723 (-1675 1250);
FORCEPROP 1 LAST VALUE 0
J 2
(-1775 1325);
DISPLAY 0.978723 (-1775 1325);
FORCEPROP 1 LAST MATERIAL CHIP
J 0
(-1875 1375);
DISPLAY 0.978723 (-1875 1375);
FORCEPROP 2 LAST CDS_LIB pure_quanta
J 0
(-1625 1325);
DISPLAY INVISIBLE (-1625 1325);
FORCEPROP 1 LAST PATH I97
J 0
(-1675 1475);
DISPLAY 0.978723 (-1675 1475);
PAINT WHITE (-1675 1475);
DISPLAY INVISIBLE (-1675 1475);
FORCEPROP 1 LAST LOCATION R381
J 0
(-1675 1375);
DISPLAY 0.978723 (-1675 1375);
FORCEPROP 1 LASTPIN (-1725 1325) $PN 1
J 0
(-1713 1337);
DISPLAY 0.787234 (-1713 1337);
PAINT MONO (-1713 1337);
FORCEPROP 1 LASTPIN (-1525 1325) $PN 2
J 0
(-1563 1337);
DISPLAY 0.787234 (-1563 1337);
PAINT MONO (-1563 1337);
FORCEPROP 0 LAST $SEC 1
J 0
(-1675 1475);
DISPLAY 0.680851 (-1675 1475);
PAINT MONO (-1675 1475);
DISPLAY INVISIBLE (-1675 1475);
FORCEPROP 0 LAST CDS_SEC 1
J 0
(-1675 1475);
DISPLAY 0.680851 (-1675 1475);
DISPLAY INVISIBLE (-1675 1475);
FORCEADD OFFPAGE..4
R 2
(-3500 -1800);
FORCEPROP 2 LAST $XR0 52 
J 0
(-3721 -1800);
DISPLAY 0.638298 (-3721 -1800);
PAINT MONO (-3721 -1800);
FORCEPROP 1 LAST COMMENT_BODY TRUE
J 2
(-3475 -1900);
DISPLAY 0.872340 (-3475 -1900);
PAINT PEACH (-3475 -1900);
DISPLAY INVISIBLE (-3475 -1900);
FORCEPROP 1 LAST OFFPAGE TRUE
J 2
(-3825 -1925);
DISPLAY 0.872340 (-3825 -1925);
PAINT GREEN (-3825 -1925);
DISPLAY INVISIBLE (-3825 -1925);
FORCEPROP 2 LAST CDS_LIB standard
J 0
(-3500 -1800);
DISPLAY INVISIBLE (-3500 -1800);
FORCEPROP 2 LAST PATH I99
J 0
(-3700 -1750);
DISPLAY 0.680851 (-3700 -1750);
DISPLAY INVISIBLE (-3700 -1750);
FORCEADD QUANTA_TITLE_BLOCK_C..1
(5500 -3150);
FORCEPROP 0 LAST CDS_CON_LAST_MODIFIED Fri Aug 25 17:25:48 2023
J 0
(3615 -3135);
DISPLAY INVISIBLE (3615 -3135);
FORCEPROP 2 LAST Q_DEPT 
J 1
(1737 -3101);
DISPLAY 1.957447 (1737 -3101);
PAINT GREEN (1737 -3101);
FORCEPROP 1 LAST CUSTOM_TXT_CDS <CON_LAST_MODIFIED>
J 0
(3615 -3135);
DISPLAY 0.978723 (3615 -3135);
FORCEPROP 2 LAST CUSTOM_TXT_CDS <XR_PAGE_TITLE>
J 0
(-2390 2100);
DISPLAY 0.638298 (-2390 2100);
PAINT PINK (-2390 2100);
DISPLAY INVISIBLE (-2390 2100);
FORCEPROP 1 LAST CUSTOM_TXT_CDS <NAME_2>
J 0
(2325 -3100);
FORCEPROP 1 LAST CUSTOM_TXT_CDS <NAME_1>
J 0
(2325 -2975);
FORCEPROP 1 LAST CUSTOM_TXT_CDS <Q_NUMBER>
J 0
(4097 -3047);
DISPLAY 1.212766 (4097 -3047);
FORCEPROP 1 LAST CUSTOM_TXT_CDS <Q_PROJ>
J 0
(3118 -3048);
DISPLAY 1.212766 (3118 -3048);
FORCEPROP 1 LAST CUSTOM_TXT_CDS <Q_REV>
J 0
(5316 -3047);
DISPLAY 1.212766 (5316 -3047);
FORCEPROP 1 LAST CUSTOM_TXT_CDS <CON_PAGE_NUM> OF <CON_TOTAL_PAGES>
J 0
(5054 -3132);
DISPLAY 0.978723 (5054 -3132);
FORCEPROP 1 LAST Q_TITLE MPQ8626 - P3V3_AUX
J 0
(-3825 -3125);
DISPLAY 2.446809 (-3825 -3125);
PAINT GREEN (-3825 -3125);
FORCEPROP 2 LAST PAGE_BORDER TRUE
J 0
(-2390 2100);
DISPLAY 0.638298 (-2390 2100);
PAINT PINK (-2390 2100);
DISPLAY INVISIBLE (-2390 2100);
FORCEPROP 1 LAST CDS_LMAN_SYM_OUTLINE -9475,6775,100,-125
J 0
(5500 -3150);
DISPLAY 0.468085 (5500 -3150);
PAINT GREEN (5500 -3150);
DISPLAY INVISIBLE (5500 -3150);
FORCEPROP 2 LAST CDS_LIB pure_quanta
J 0
(5500 -3150);
DISPLAY INVISIBLE (5500 -3150);
FORCEPROP 1 LAST COMMENT_BODY TRUE
J 0
(5512 -3163);
DISPLAY 0.978723 (5512 -3163);
PAINT PEACH (5512 -3163);
DISPLAY INVISIBLE (5512 -3163);
FORCEPROP 2 LAST CDS_XR_PAGE_TITLE CR-52 : @SCM_LIB.SCM(SCH_1):PAGE52
J 0
(-2390 2100);
DISPLAY 0.638298 (-2390 2100);
PAINT PINK (-2390 2100);
DISPLAY INVISIBLE (-2390 2100);
FORCEADD DNS..2
(375 -1525);
PAINT RED (375 -1525);
FORCEPROP 1 LAST COMMENT_BODY TRUE
R 1
J 0
(450 -1750);
DISPLAY 0.872340 (450 -1750);
PAINT PEACH (450 -1750);
DISPLAY INVISIBLE (450 -1750);
FORCEPROP 2 LAST CDS_LIB mstr_misc
J 0
(375 -1525);
DISPLAY INVISIBLE (375 -1525);
FORCEADD DNS..2
(-75 -2050);
PAINT RED (-75 -2050);
FORCEPROP 2 LAST CDS_LIB mstr_misc
J 0
(-75 -2050);
DISPLAY INVISIBLE (-75 -2050);
FORCEPROP 1 LAST COMMENT_BODY TRUE
R 1
J 0
(0 -2275);
DISPLAY 0.872340 (0 -2275);
PAINT PEACH (0 -2275);
DISPLAY INVISIBLE (0 -2275);
FORCEADD DNS..2
(-2525 -1550);
PAINT RED (-2525 -1550);
FORCEPROP 1 LAST COMMENT_BODY TRUE
R 1
J 0
(-2450 -1775);
DISPLAY 0.872340 (-2450 -1775);
PAINT PEACH (-2450 -1775);
DISPLAY INVISIBLE (-2450 -1775);
FORCEPROP 2 LAST CDS_LIB mstr_misc
J 0
(-2525 -1550);
DISPLAY INVISIBLE (-2525 -1550);
FORCEADD DNS..2
(-1650 1550);
PAINT RED (-1650 1550);
FORCEPROP 1 LAST COMMENT_BODY TRUE
R 1
J 0
(-1575 1325);
DISPLAY 0.872340 (-1575 1325);
PAINT PEACH (-1575 1325);
DISPLAY INVISIBLE (-1575 1325);
FORCEPROP 2 LAST CDS_LIB mstr_misc
J 0
(-1650 1550);
DISPLAY INVISIBLE (-1650 1550);
FORCEADD DNS..2
(2150 1625);
PAINT RED (2150 1625);
FORCEPROP 1 LAST COMMENT_BODY TRUE
R 1
J 0
(2225 1400);
DISPLAY 0.872340 (2225 1400);
PAINT PEACH (2225 1400);
DISPLAY INVISIBLE (2225 1400);
FORCEPROP 2 LAST CDS_LIB mstr_misc
J 0
(2150 1625);
DISPLAY INVISIBLE (2150 1625);
FORCEADD CAD_NOTE..1
(-1025 -650);
FORCEPROP 0 LAST L1 THE CAP & DAMPING RS FOR PWRGD SHOULD CLOSE TO DRIVE-END
J 0
(-1075 -850);
DISPLAY 1.021277 (-1075 -850);
PAINT WHITE (-1075 -850);
FORCEPROP 2 LAST CDS_LIB logical_power
J 0
(-1025 -650);
DISPLAY INVISIBLE (-1025 -650);
FORCEPROP 1 LAST COMMENT_BODY TRUE
J 0
(-1000 -550);
DISPLAY 0.978723 (-1000 -550);
PAINT PEACH (-1000 -550);
DISPLAY INVISIBLE (-1000 -550);
FORCEADD CAD_NOTE..1
(1075 2200);
FORCEPROP 0 LAST L1 THE CAP & DAMPING RS FOR PWRGD SHOULD CLOSE TO DRIVE-END
J 0
(1025 2000);
DISPLAY 1.021277 (1025 2000);
PAINT WHITE (1025 2000);
FORCEPROP 1 LAST COMMENT_BODY TRUE
J 0
(1100 2300);
DISPLAY 0.978723 (1100 2300);
PAINT PEACH (1100 2300);
DISPLAY INVISIBLE (1100 2300);
FORCEPROP 2 LAST CDS_LIB logical_power
J 0
(1075 2200);
DISPLAY INVISIBLE (1075 2200);
WIRE 16 -1 (-3375 2300)(-3375 2600);
WIRE 16 -1 (-3375 2225)(-3375 2300);
WIRE 16 -1 (-3025 2300)(-3375 2300);
WIRE 16 -1 (-900 -1075)(-900 -1125);
WIRE 16 -1 (-1700 -1000)(-1700 -1075);
WIRE 16 -1 (3900 -825)(3900 -775);
WIRE 16 -1 (3900 -825)(3550 -825);
WIRE 16 -1 (2250 3275)(2250 3200);
WIRE 16 -1 (325 2175)(325 2225);
WIRE 16 -1 (5125 1325)(5125 1400);
WIRE 16 -1 (5125 1325)(5125 475);
WIRE 16 -1 (5125 1325)(4650 1325);
WIRE 16 -1 (-775 -1400)(-775 -1475);
WIRE 16 -1 (2925 -1750)(2925 -1825);
WIRE 16 -1 (3550 -1650)(3550 -1775);
WIRE 16 -1 (3900 -1025)(3900 -1050);
WIRE 16 -1 (2175 1525)(2175 1475);
WIRE 16 -1 (1075 2425)(1075 2350);
WIRE 16 -1 (1075 2425)(1175 2425);
WIRE 16 -1 (2250 3000)(2250 2950);
WIRE 16 -1 (-3375 2025)(-3375 1975);
WIRE 16 -1 (325 475)(325 275);
WIRE 16 -1 (325 525)(325 475);
WIRE 16 -1 (125 475)(325 475);
WIRE 16 -1 (4475 850)(4475 800);
WIRE 16 -1 (4475 850)(4325 850);
WIRE 16 -1 (4650 850)(4475 850);
WIRE 16 -1 (-1600 400)(-1600 250);
WIRE 16 -1 (-2125 1825)(-2125 1775);
WIRE 16 -1 (-2125 1825)(-1725 1825);
WIRE 16 -1 (-2125 1950)(-2125 1825);
WIRE 16 -1 (-2500 1825)(-2125 1825);
WIRE 16 -1 (-875 -2200)(-875 -1750);
WIRE 16 -1 (-1975 -1350)(-1975 -1425);
WIRE 16 -1 (-50 -2150)(-50 -2225);
WIRE 16 -1 (-1200 50)(-1200 -100);
WIRE 16 -1 (800 50)(800 -100);
WIRE 16 -1 (-2025 650)(-2025 500);
WIRE 16 -1 (1300 -25)(1300 -150);
WIRE 16 -1 (125 725)(325 725);
WIRE 16 -1 (125 525)(325 525);
WIRE 16 -1 (325 525)(325 725);
WIRE 16 -1 (-875 -1750)(-950 -1750);
WIRE 16 3135 (-3750 -2775)(-3750 -550);
WIRE 16 3135 (-3750 -2775)(5325 -2775);
WIRE 16 3135 (5325 -550)(-3750 -550);
WIRE 16 3135 (5325 -550)(5325 -2775);
WIRE 16 -1 (-3450 -1800)(-2600 -1800);
FORCEPROP 0 LAST SIG_NAME EN_P3V3_RGM
J 0
(-3435 -1790);
DISPLAY 0.808511 (-3435 -1790);
WIRE 16 -1 (-2400 -1800)(-2175 -1800);
FORCEPROP 0 LAST SIG_NAME EN_P3V3_RGM_R
J 0
(-2310 -1790);
DISPLAY 0.808511 (-2310 -1790);
WIRE 16 -1 (-2175 -1800)(-1600 -1800);
WIRE 16 -1 (-2175 -1550)(-2175 -1800);
WIRE 16 -1 (-2400 -1550)(-2175 -1550);
WIRE 16 -1 (-3450 -1550)(-2600 -1550);
FORCEPROP 0 LAST SIG_NAME PWRGD_P1V8_AUX_R3
J 0
(-3435 -1540);
DISPLAY 0.808511 (-3435 -1540);
WIRE 16 -1 (-1700 -1700)(-1600 -1700);
WIRE 16 -1 (-1975 -1075)(-1975 -1150);
WIRE 16 -1 (-1700 -1075)(-1700 -1700);
WIRE 16 -1 (-1700 -1075)(-1975 -1075);
WIRE 16 3135 (-875 -1725)(-475 -1725);
WIRE 16 3135 (-875 -1625)(-875 -1725);
WIRE 16 3135 (-475 -1725)(-475 -1625);
WIRE 16 3135 (-475 -1625)(-875 -1625);
WIRE 16 -1 (-950 -1700)(-900 -1700);
WIRE 16 -1 (-725 -1700)(-900 -1700);
WIRE 16 -1 (-900 -1700)(-900 -1125);
WIRE 16 -1 (-775 -1125)(-900 -1125);
WIRE 16 -1 (-775 -1200)(-775 -1125);
WIRE 16 2175 (-2275 250)(-2275 -125);
WIRE 16 2175 (-3400 -125)(-2275 -125);
WIRE 16 2175 (-3400 250)(-2275 250);
WIRE 16 2175 (-3400 250)(-3400 -125);
WIRE 16 -1 (325 1825)(125 1825);
WIRE 16 -1 (325 1975)(325 1825);
WIRE 16 -1 (2175 1825)(2175 1725);
WIRE 16 -1 (2175 1825)(2875 1825);
WIRE 16 -1 (2175 1825)(325 1825);
FORCEPROP 2 LAST SIG_NAME PWRGD_P3V3_AUX_R
J 2
(1790 1835);
DISPLAY 0.808511 (1790 1835);
WIRE 16 3135 (775 1600)(925 1600);
WIRE 16 3135 (775 1725)(775 1600);
WIRE 16 3135 (925 1600)(925 1725);
WIRE 16 3135 (925 1725)(775 1725);
WIRE 16 -1 (1350 1625)(950 1625);
FORCEPROP 2 LAST SIG_NAME SW_P3V3_AUX_BST
J 0
(965 1635);
DISPLAY 0.638298 (965 1635);
WIRE 16 -1 (1350 1575)(1350 1625);
WIRE 16 2175 (3475 2975)(5253 2975);
WIRE 16 2175 (5253 2975)(5253 2100);
WIRE 16 2175 (3475 2975)(3475 2100);
WIRE 16 2175 (3475 2100)(5253 2100);
WIRE 16 -1 (-2025 1125)(-675 1125);
FORCEPROP 2 LAST SIG_NAME P3V3_AUX_MODE
J 0
(-1710 1135);
DISPLAY 0.808511 (-1710 1135);
WIRE 16 -1 (-2025 850)(-2025 1125);
WIRE 16 -1 (-675 1825)(-725 1825);
WIRE 16 -1 (-725 1825)(-725 2300);
WIRE 16 -1 (-1175 2300)(-1175 2150);
WIRE 16 -1 (-725 2300)(-1175 2300);
WIRE 16 -1 (-1725 2150)(-1725 2300);
WIRE 16 -1 (-1725 2300)(-1175 2300);
WIRE 16 -1 (-2125 2150)(-2125 2300);
WIRE 16 -1 (-2125 2300)(-1725 2300);
WIRE 16 -1 (-2500 2150)(-2500 2300);
WIRE 16 -1 (-2500 2300)(-2125 2300);
WIRE 16 -1 (-2825 2300)(-2500 2300);
FORCEPROP 2 LAST SIG_NAME SW_P3V3_AUX_FLT
J 0
(-2610 2310);
DISPLAY 0.808511 (-2610 2310);
WIRE 16 -1 (-2675 1550)(-1725 1550);
FORCEPROP 0 LAST SIG_NAME EN_P3V3_R1
J 0
(-2560 1560);
DISPLAY 0.808511 (-2560 1560);
WIRE 16 -1 (-2675 1325)(-1725 1325);
FORCEPROP 0 LAST SIG_NAME EN_P3V3
J 0
(-2560 1335);
DISPLAY 0.808511 (-2560 1335);
WIRE 16 -1 (1350 1375)(1350 1325);
WIRE 16 -1 (1750 1325)(1350 1325);
WIRE 16 -1 (125 1325)(275 1325);
WIRE 16 -1 (275 1325)(1350 1325);
FORCEPROP 2 LAST SIG_NAME SW_P3V3_AUX_SW
J 0
(340 1335);
DISPLAY 0.808511 (340 1335);
WIRE 16 -1 (275 1375)(275 1325);
WIRE 16 -1 (125 1375)(275 1375);
WIRE 16 -1 (4650 975)(4650 850);
WIRE 16 -1 (4325 975)(4325 850);
WIRE 16 -1 (4000 975)(4000 850);
WIRE 16 -1 (4000 850)(4325 850);
WIRE 16 -1 (3650 975)(3650 850);
WIRE 16 -1 (4000 850)(3650 850);
WIRE 16 -1 (3175 850)(3650 850);
WIRE 16 -1 (3175 975)(3175 850);
WIRE 16 -1 (1950 1325)(3175 1325);
WIRE 16 -1 (3175 1175)(3175 1325);
WIRE 16 -1 (3175 1325)(3650 1325);
WIRE 16 -1 (3650 1175)(3650 1325);
WIRE 16 -1 (4000 1325)(3650 1325);
WIRE 16 -1 (4000 1175)(4000 1325);
WIRE 16 -1 (4000 1325)(4325 1325);
WIRE 16 -1 (4325 1175)(4325 1325);
WIRE 16 -1 (4325 1325)(4650 1325);
WIRE 16 -1 (4650 1325)(4650 1175);
WIRE 16 -1 (3650 475)(3300 475);
WIRE 16 -1 (5125 475)(3650 475);
WIRE 16 -1 (3650 125)(3650 475);
WIRE 16 -1 (3300 125)(3650 125);
WIRE 16 -1 (3550 -1150)(3550 -825);
WIRE 16 -1 (4500 -1400)(3900 -1400);
FORCEPROP 2 LAST SIG_NAME EN_P3V3_RGM
J 0
(4040 -1390);
DISPLAY 0.808511 (4040 -1390);
WIRE 16 -1 (300 -1525)(200 -1525);
WIRE 16 -1 (200 -1700)(300 -1700);
WIRE 16 -1 (200 -1525)(200 -1700);
WIRE 16 -1 (-50 -1700)(-50 -1950);
WIRE 16 -1 (-50 -1700)(200 -1700);
WIRE 16 -1 (-525 -1700)(-50 -1700);
FORCEPROP 2 LAST SIG_NAME PWRGD_P3V3_RGM_R
J 0
(-435 -1690);
DISPLAY 0.808511 (-435 -1690);
WIRE 16 -1 (500 -1525)(1325 -1525);
FORCEPROP 2 LAST SIG_NAME PWRGD_P3V3_RGM_R3
J 0
(690 -1515);
DISPLAY 0.808511 (690 -1515);
WIRE 16 -1 (-350 -1800)(-950 -1800);
FORCEPROP 2 LAST SIG_NAME TP_U14_FLAG_N
J 0
(-860 -1790);
DISPLAY 0.808511 (-860 -1790);
PAINT WHITE (-860 -1790);
WIRE 16 -1 (1300 875)(125 875);
WIRE 16 -1 (1300 875)(1300 475);
WIRE 16 -1 (1300 175)(1300 475);
WIRE 16 -1 (1300 475)(2725 475);
FORCEPROP 2 LAST SIG_NAME P3V3_AUX_FB_RC
J 0
(1915 485);
DISPLAY 0.808511 (1915 485);
WIRE 16 -1 (3100 475)(2725 475);
WIRE 16 -1 (2725 125)(2725 475);
WIRE 16 -1 (3100 125)(2725 125);
WIRE 16 -1 (125 1625)(750 1625);
FORCEPROP 2 LAST SIG_NAME SW_P3V3_AUX_BST_R
J 0
(215 1635);
DISPLAY 0.680851 (215 1635);
WIRE 16 -1 (3050 2425)(2275 2425);
FORCEPROP 2 LAST SIG_NAME EN_P3V3
J 2
(2990 2435);
DISPLAY 0.808511 (2990 2435);
WIRE 16 -1 (550 2575)(1175 2575);
FORCEPROP 0 LAST SIG_NAME PWRGD_P1V8_AUX
J 0
(540 2585);
DISPLAY 0.808511 (540 2585);
WIRE 16 -1 (-2500 1950)(-2500 1825);
WIRE 16 -1 (-1725 1950)(-1725 1825);
WIRE 16 -1 (-1175 1825)(-1725 1825);
WIRE 16 -1 (-1175 1950)(-1175 1825);
WIRE 16 -1 (-1525 1550)(-1450 1550);
WIRE 16 -1 (-1450 1550)(-1450 1325);
WIRE 16 -1 (-1450 1325)(-675 1325);
FORCEPROP 0 LAST SIG_NAME PWRGD_EN_P3V3_R
J 0
(-1410 1335);
DISPLAY 0.808511 (-1410 1335);
WIRE 16 -1 (-1525 1325)(-1450 1325);
WIRE 16 -1 (125 625)(800 625);
FORCEPROP 2 LAST SIG_NAME P3V3_AUX_REF
J 0
(390 635);
DISPLAY 0.808511 (390 635);
WIRE 16 -1 (800 625)(800 250);
WIRE 16 -1 (-1200 250)(-1200 525);
WIRE 16 -1 (-1200 525)(-675 525);
FORCEPROP 2 LAST SIG_NAME P3V3_AUX_CS
J 0
(-1160 535);
DISPLAY 0.808511 (-1160 535);
WIRE 16 -1 (-1600 875)(-675 875);
FORCEPROP 2 LAST SIG_NAME P3V3_AUX_VCC
J 0
(-1585 885);
DISPLAY 0.808511 (-1585 885);
WIRE 16 -1 (-1600 600)(-1600 875);
WIRE 16 -1 (2925 -1550)(2925 -1450);
WIRE 16 -1 (2925 -1450)(3300 -1450);
WIRE 16 -1 (2575 -1450)(2925 -1450);
FORCEPROP 2 LAST SIG_NAME PWRGD_P1V8_AUX_R2
J 0
(2665 -1440);
DISPLAY 0.680851 (2665 -1440);
WIRE 16 -1 (1800 -1450)(2375 -1450);
FORCEPROP 0 LAST SIG_NAME PWRGD_P1V8_AUX
J 0
(1765 -1440);
DISPLAY 0.808511 (1765 -1440);
WIRE 16 -1 (500 -1700)(1325 -1700);
FORCEPROP 2 LAST SIG_NAME PWRGD_P3V3_RGM
J 0
(690 -1690);
DISPLAY 0.808511 (690 -1690);
WIRE 16 -1 (2825 -1100)(3300 -1100);
FORCEPROP 0 LAST SIG_NAME PWRGD_P5V_AUX
J 0
(2815 -1090);
DISPLAY 0.808511 (2815 -1090);
WIRE 16 -1 (3300 -1100)(3300 -1350);
WIRE 16 -1 (2250 3200)(2650 3200);
WIRE 16 -1 (2650 2775)(2650 3200);
WIRE 16 -1 (2275 2775)(2650 2775);
WIRE 16 -1 (3075 1825)(3775 1825);
FORCEPROP 2 LAST SIG_NAME PWRGD_P3V3_AUX
J 2
(3690 1835);
DISPLAY 0.808511 (3690 1835);
WIRE 16 -1 (550 2775)(1175 2775);
FORCEPROP 0 LAST SIG_NAME PWRGD_P5V_AUX
J 0
(540 2785);
DISPLAY 0.808511 (540 2785);
DOT 1 (1350 1325);
DOT 1 (3650 475);
DOT 1 (-900 -1700);
DOT 1 (-900 -1125);
DOT 1 (-1725 1825);
DOT 1 (-1450 1325);
DOT 1 (325 475);
DOT 1 (200 -1700);
DOT 1 (-1700 -1075);
DOT 1 (325 1825);
DOT 1 (2925 -1450);
DOT 1 (-3375 2300);
DOT 1 (-2500 2300);
DOT 1 (-1175 2300);
DOT 1 (4000 1325);
DOT 1 (2175 1825);
DOT 1 (325 525);
DOT 1 (2725 475);
DOT 1 (1300 475);
DOT 1 (-2125 1825);
DOT 1 (3650 1325);
DOT 1 (4650 1325);
DOT 1 (3650 850);
DOT 1 (5125 1325);
DOT 1 (4475 850);
DOT 1 (-1725 2300);
DOT 1 (4000 850);
DOT 1 (4325 1325);
DOT 1 (3175 1325);
DOT 1 (4325 850);
DOT 1 (275 1325);
DOT 1 (-2125 2300);
DOT 1 (-50 -1700);
DOT 1 (-2175 -1800);
FORCENOTE
PCMC063T_3R3MN
(1600 1225) 0;
DISPLAY LEFT (1600 1225);
DISPLAY 1.021277 (1600 1225);
FORCENOTE
6.5*6.9*3.0
(1600 1150) 0;
DISPLAY LEFT (1600 1150);
DISPLAY 1.021277 (1600 1150);
FORCENOTE
ISAT=13.5A
(1600 1075) 0;
DISPLAY LEFT (1600 1075);
DISPLAY 1.021277 (1600 1075);
FORCENOTE
DCR=28MOHM
(1600 1000) 0;
DISPLAY LEFT (1600 1000);
DISPLAY 1.021277 (1600 1000);
FORCENOTE
P3V3_AUX
(-1500 3000) 0;
DISPLAY LEFT (-1500 3000);
DISPLAY 3.148936 (-1500 3000);
FORCENOTE
PWRGD_UP DELAY 230US
(2900 -2300) 0;
DISPLAY LEFT (2900 -2300);
DISPLAY 1.170213 (2900 -2300);
FORCENOTE
WORK FREQUENCY=600KHZ
(3512 2194) 0;
DISPLAY LEFT (3512 2194);
DISPLAY 0.936170 (3512 2194);
FORCENOTE
OVER CURRENT PROTECTION(IC RATING)=6A
(3512 2419) 0;
DISPLAY LEFT (3512 2419);
DISPLAY 0.936170 (3512 2419);
FORCENOTE
DESIGN SPECIFICATION
(3512 2894) 0;
DISPLAY LEFT (3512 2894);
DISPLAY 1.170213 (3512 2894);
FORCENOTE
OUTPUT VOLTAGE=3.3V
(3512 2794) 0;
DISPLAY LEFT (3512 2794);
DISPLAY 1.042553 (3512 2794);
FORCENOTE
CURRENT STEP=0.9A
(3512 2344) 0;
DISPLAY LEFT (3512 2344);
DISPLAY 0.936170 (3512 2344);
FORCENOTE
SLEW RATE=0.25A/US
(3512 2269) 0;
DISPLAY LEFT (3512 2269);
DISPLAY 0.936170 (3512 2269);
FORCENOTE
2ND AL053317005
(-3300 -50) 0;
DISPLAY LEFT (-3300 -50);
DISPLAY 1.170213 (-3300 -50);
FORCENOTE
1ST AL008626000
(-3300 50) 0;
DISPLAY LEFT (-3300 50);
DISPLAY 1.170213 (-3300 50);
FORCENOTE
IC TABLE
(-3300 150) 0;
DISPLAY LEFT (-3300 150);
DISPLAY 1.170213 (-3300 150);
FORCENOTE
OUTPUT RIPPLE=+/-1%
(3512 2719) 0;
DISPLAY LEFT (3512 2719);
DISPLAY 0.936170 (3512 2719);
FORCENOTE
TRANSIENT TOLERANCE=+/-5%
(3512 2644) 0;
DISPLAY LEFT (3512 2644);
DISPLAY 0.936170 (3512 2644);
FORCENOTE
TDC=3.6A
(3512 2569) 0;
DISPLAY LEFT (3512 2569);
DISPLAY 0.936170 (3512 2569);
FORCENOTE
MAX CURRENT=4.1A
(3512 2494) 0;
DISPLAY LEFT (3512 2494);
DISPLAY 0.936170 (3512 2494);
FORCENOTE
CHANGE TO 2R2_20220804
(550 1775) 0;
DISPLAY LEFT (550 1775);
DISPLAY 0.808511 (550 1775);
PAINT WHITE (550 1775);
FORCENOTE
FOR BMC POWER DOMAIN: P3V3_RGM
(-3600 -750) 0;
DISPLAY LEFT (-3600 -750);
DISPLAY 1.595745 (-3600 -750);
PAINT WHITE (-3600 -750);
FORCENOTE
CHANGE TO 2.2K_20220426
(-800 -1600) 0;
DISPLAY LEFT (-800 -1600);
DISPLAY 0.808511 (-800 -1600);
PAINT WHITE (-800 -1600);
QUIT
